# Altium SchDoc records: 02-Antenna_Supervisor.SchDoc
|HEADER=Protel for Windows - Schematic Capture Binary File Version 5.0|Weight=1144|MinorVersion=9
|RECORD=31|FontIdCount=5|Size1=10|FontName1=Times New Roman|Size2=10|Rotation2=90|FontName2=Times New Roman|Size3=10|Underline3=T|FontName3=Times New Roman|Size4=14|FontName4=Times New Roman|Size5=30|FontName5=Times New Roman|UseMBCS=T|IsBOC=T|HotSpotGridOn=T|HotSpotGridSize=4|SheetStyle=5|SystemFont=1|BorderOn=T|TitleBlockOn=T|SheetNumberSpaceSize=12|AreaColor=16317695|SnapGridOn=T|SnapGridSize=10|VisibleGridOn=T|VisibleGridSize=10|CustomX=1500|CustomY=950|CustomXZones=6|CustomYZones=4|CustomMarginWidth=20|Display_Unit=0
|RECORD=41|OwnerPartId=-1|Color=8388608|FontID=1|IsHidden=T|Text=*|Name=CurrentTime|ReadOnlyState=1
|RECORD=41|IndexInSheet=1|OwnerPartId=-1|Color=8388608|FontID=1|IsHidden=T|Text=*|Name=CurrentDate|ReadOnlyState=1
|RECORD=41|IndexInSheet=2|OwnerPartId=-1|Color=8388608|FontID=1|IsHidden=T|Text=*|Name=Time|ReadOnlyState=1
|RECORD=41|IndexInSheet=3|OwnerPartId=-1|Color=8388608|FontID=1|IsHidden=T|Text=*|Name=Date|ReadOnlyState=1
|RECORD=41|IndexInSheet=4|OwnerPartId=-1|Color=8388608|FontID=1|IsHidden=T|Text=*|Name=DocumentFullPathAndName|ReadOnlyState=1
|RECORD=41|IndexInSheet=5|OwnerPartId=-1|Color=8388608|FontID=1|IsHidden=T|Text=*|Name=DocumentName|ReadOnlyState=1
|RECORD=41|IndexInSheet=6|OwnerPartId=-1|Color=8388608|FontID=1|IsHidden=T|Text=*|Name=ModifiedDate|ReadOnlyState=1
|RECORD=41|IndexInSheet=7|OwnerPartId=-1|Color=8388608|FontID=1|IsHidden=T|Text=*|Name=ApprovedBy|ReadOnlyState=1
|RECORD=41|IndexInSheet=8|OwnerPartId=-1|Color=8388608|FontID=1|IsHidden=T|Text=*|Name=CheckedBy|ReadOnlyState=1
|RECORD=41|IndexInSheet=9|OwnerPartId=-1|Color=8388608|FontID=1|IsHidden=T|Text=*|Name=Author|ReadOnlyState=1
|RECORD=41|IndexInSheet=10|OwnerPartId=-1|Color=8388608|FontID=1|IsHidden=T|Text=*|Name=CompanyName|ReadOnlyState=1
|RECORD=41|IndexInSheet=11|OwnerPartId=-1|Color=8388608|FontID=1|IsHidden=T|Text=*|Name=DrawnBy|ReadOnlyState=1
|RECORD=41|IndexInSheet=12|OwnerPartId=-1|Color=8388608|FontID=1|IsHidden=T|Text=*|Name=Engineer|ReadOnlyState=1
|RECORD=41|IndexInSheet=13|OwnerPartId=-1|Color=8388608|FontID=1|IsHidden=T|Text=*|Name=Organization|ReadOnlyState=1
|RECORD=41|IndexInSheet=14|OwnerPartId=-1|Color=8388608|FontID=1|IsHidden=T|Text=*|Name=Address1|ReadOnlyState=1
|RECORD=41|IndexInSheet=15|OwnerPartId=-1|Color=8388608|FontID=1|IsHidden=T|Text=*|Name=Address2|ReadOnlyState=1
|RECORD=41|IndexInSheet=16|OwnerPartId=-1|Color=8388608|FontID=1|IsHidden=T|Text=*|Name=Address3|ReadOnlyState=1
|RECORD=41|IndexInSheet=17|OwnerPartId=-1|Color=8388608|FontID=1|IsHidden=T|Text=*|Name=Address4|ReadOnlyState=1
|RECORD=41|IndexInSheet=18|OwnerPartId=-1|Color=8388608|FontID=1|IsHidden=T|Text=*|Name=Title|ReadOnlyState=1
|RECORD=41|IndexInSheet=19|OwnerPartId=-1|Color=8388608|FontID=1|IsHidden=T|Text=*|Name=DocumentNumber|ReadOnlyState=1
|RECORD=41|IndexInSheet=20|OwnerPartId=-1|Color=8388608|FontID=1|IsHidden=T|Text=*|Name=Revision|ReadOnlyState=1
|RECORD=41|IndexInSheet=21|OwnerPartId=-1|Color=8388608|FontID=1|IsHidden=T|Text=2|Name=SheetNumber|ReadOnlyState=1
|RECORD=41|IndexInSheet=22|OwnerPartId=-1|Color=8388608|FontID=1|IsHidden=T|Text=3|Name=SheetTotal|ReadOnlyState=1
|RECORD=41|IndexInSheet=23|OwnerPartId=-1|Color=8388608|FontID=1|IsHidden=T|Text=*|Name=Rule|ReadOnlyState=1
|RECORD=41|IndexInSheet=24|OwnerPartId=-1|Color=8388608|FontID=1|IsHidden=T|Text=*|Name=ImagePath|ReadOnlyState=1
|RECORD=41|IndexInSheet=25|OwnerPartId=-1|Color=8388608|FontID=1|IsHidden=T|Text=*|Name=ProjectName|ReadOnlyState=1
|RECORD=41|IndexInSheet=26|OwnerPartId=-1|Color=8388608|FontID=1|IsHidden=T|Text=*|Name=Application_BuildNumber|ReadOnlyState=1
|RECORD=1|LibReference=1029c3af85768c4190bb7ad29bc67b5|ComponentDescription=1kO ±1% 0.063W 0402 Thick Film Chip Resistor AEC-Q200 compliant|PartCount=2|DisplayModeCount=1|IndexInSheet=27|OwnerPartId=-1|Location.X=460|Location.Y=440|Orientation=1|CurrentPartId=1|LibraryPath=*|SourceLibraryName=Altium Content Vault|TargetFileName=*|AreaColor=11599871|Color=128|PartIDLocked=T|DesignItemId=CMP-26527-000026-1|AllPinCount=2
|RECORD=2|OwnerIndex=28|OwnerPartId=1|Electrical=4|PinConglomerate=35|PinLength=20|Location.X=460|Location.Y=460|Name=1|Designator=1|PinPropagationDelay=0.000000E+000
|RECORD=2|OwnerIndex=28|OwnerPartId=1|Electrical=4|PinConglomerate=33|PinLength=20|Location.X=460|Location.Y=490|Name=2|Designator=2|PinPropagationDelay=0.000000E+000
|RECORD=13|OwnerIndex=28|IsNotAccesible=T|IndexInSheet=2|OwnerPartId=1|Location.X=460|Location.Y=460|Corner.X=455|Corner.Y=463|LineWidth=1|Color=16711680
|RECORD=13|OwnerIndex=28|IsNotAccesible=T|IndexInSheet=3|OwnerPartId=1|Location.X=455|Location.Y=463|Corner.X=465|Corner.Y=468|LineWidth=1|Color=16711680
|RECORD=13|OwnerIndex=28|IsNotAccesible=T|IndexInSheet=4|OwnerPartId=1|Location.X=465|Location.Y=468|Corner.X=455|Corner.Y=473|LineWidth=1|Color=16711680
|RECORD=13|OwnerIndex=28|IsNotAccesible=T|IndexInSheet=5|OwnerPartId=1|Location.X=455|Location.Y=473|Corner.X=465|Corner.Y=478|LineWidth=1|Color=16711680
|RECORD=13|OwnerIndex=28|IsNotAccesible=T|IndexInSheet=6|OwnerPartId=1|Location.X=465|Location.Y=478|Corner.X=455|Corner.Y=483|LineWidth=1|Color=16711680
|RECORD=13|OwnerIndex=28|IsNotAccesible=T|IndexInSheet=7|OwnerPartId=1|Location.X=455|Location.Y=483|Corner.X=465|Corner.Y=488|LineWidth=1|Color=16711680
|RECORD=13|OwnerIndex=28|IsNotAccesible=T|IndexInSheet=8|OwnerPartId=1|Location.X=465|Location.Y=488|Corner.X=460|Corner.Y=490|LineWidth=1|Color=16711680
|RECORD=13|OwnerIndex=28|IsNotAccesible=T|IndexInSheet=9|OwnerPartId=1|Location.X=460|Location.Y=460|Corner.X=460|Corner.Y=457|LineWidth=1|Color=16711680
|RECORD=13|OwnerIndex=28|IsNotAccesible=T|IndexInSheet=10|OwnerPartId=1|Location.X=460|Location.Y=490|Corner.X=460|Corner.Y=493|LineWidth=1|Color=16711680
|RECORD=41|OwnerIndex=28|IndexInSheet=11|OwnerPartId=-1|Location.X=454|Location.Y=512|Color=8388608|FontID=1|IsHidden=T|Text=1mm|Name=Length
|RECORD=41|OwnerIndex=28|IndexInSheet=12|OwnerPartId=-1|Location.X=454|Location.Y=512|Color=8388608|FontID=1|IsHidden=T|Text=Yes|Name=RoHS Compliant
|RECORD=41|OwnerIndex=28|IndexInSheet=13|OwnerPartId=-1|Location.X=454|Location.Y=512|Color=8388608|FontID=1|IsHidden=T|Text=Rectangular|Name=Construction
|RECORD=41|OwnerIndex=28|IndexInSheet=14|OwnerPartId=-1|Location.X=454|Location.Y=512|Color=8388608|FontID=1|IsHidden=T|Text=0.016inch|Name=Height
|RECORD=41|OwnerIndex=28|IndexInSheet=15|OwnerPartId=-1|Location.X=454|Location.Y=512|Color=8388608|FontID=1|IsHidden=T|Text=0402|Name=Size Code
|RECORD=41|OwnerIndex=28|IndexInSheet=16|OwnerPartId=-1|Location.X=454|Location.Y=512|Color=8388608|FontID=1|IsHidden=T|Text=Lead Free|Name=Lead Free
|RECORD=41|OwnerIndex=28|IndexInSheet=17|OwnerPartId=-1|Location.X=454|Location.Y=512|Color=8388608|FontID=1|IsHidden=T|Text=No|Name=Radiation Hardening
|RECORD=41|OwnerIndex=28|IndexInSheet=18|OwnerPartId=-1|Location.X=454|Location.Y=512|Color=8388608|FontID=1|IsHidden=T|Text=1%|Name=Tolerance
|RECORD=41|OwnerIndex=28|IndexInSheet=19|OwnerPartId=-1|Location.X=454|Location.Y=512|Color=8388608|FontID=1|IsHidden=T|Text=0.02inch|Name=Width
|RECORD=41|OwnerIndex=28|IndexInSheet=20|OwnerPartId=-1|Location.X=454|Location.Y=512|Color=8388608|FontID=1|IsHidden=T|Text=1kR|Name=Resistance
|RECORD=41|OwnerIndex=28|IndexInSheet=21|OwnerPartId=-1|Location.X=454|Location.Y=512|Color=8388608|FontID=1|IsHidden=T|Text=Not|Name=Military Standard
|RECORD=41|OwnerIndex=28|IndexInSheet=22|OwnerPartId=-1|Location.X=454|Location.Y=512|Color=8388608|FontID=1|IsHidden=T|Text=Thick Film|Name=Resistor Type
|RECORD=41|OwnerIndex=28|IndexInSheet=23|OwnerPartId=-1|Location.X=454|Location.Y=512|Color=8388608|FontID=1|IsHidden=T|Text=100ppm/°C|Name=Temperature Coefficient
|RECORD=41|OwnerIndex=28|IndexInSheet=24|OwnerPartId=-1|Location.X=454|Location.Y=512|Color=8388608|FontID=1|IsHidden=T|Text=2|Name=Number of Terminations
|RECORD=41|OwnerIndex=28|IndexInSheet=25|OwnerPartId=-1|Location.X=454|Location.Y=512|Color=8388608|FontID=1|IsHidden=T|Text=-55°C|Name=Min Operating Temperature
|RECORD=41|OwnerIndex=28|IndexInSheet=26|OwnerPartId=-1|Location.X=454|Location.Y=512|Color=8388608|FontID=1|IsHidden=T|Text=155°C|Name=Max Operating Temperature
|RECORD=41|OwnerIndex=28|IndexInSheet=27|OwnerPartId=-1|Location.X=454|Location.Y=512|Color=8388608|FontID=1|IsHidden=T|Text=63mW|Name=Power Rating
|RECORD=41|OwnerIndex=28|IndexInSheet=28|OwnerPartId=-1|Location.X=454|Location.Y=512|Color=8388608|FontID=1|IsHidden=T|Text=0.5mm|Name=Depth
|RECORD=41|OwnerIndex=28|IndexInSheet=29|OwnerPartId=-1|Location.X=454|Location.Y=512|Color=8388608|FontID=1|IsHidden=T|Text=Automotive AEC-Q200|Name=Features
|RECORD=41|OwnerIndex=28|IndexInSheet=30|OwnerPartId=-1|Location.X=454|Location.Y=512|Color=8388608|FontID=1|IsHidden=T|Text=Tape and Reel|Name=Packaging
|RECORD=41|OwnerIndex=28|IndexInSheet=31|OwnerPartId=-1|Location.X=454|Location.Y=512|Color=8388608|FontID=1|IsHidden=T|Text=1005|Name=Case Code (Metric)
|RECORD=41|OwnerIndex=28|IndexInSheet=32|OwnerPartId=-1|Location.X=454|Location.Y=512|Color=8388608|FontID=1|IsHidden=T|Text=Surface Mount|Name=Mount
|RECORD=41|OwnerIndex=28|IndexInSheet=33|OwnerPartId=-1|Location.X=454|Location.Y=512|Color=8388608|FontID=1|IsHidden=T|Text=Tin|Name=Contact Plating
|RECORD=41|OwnerIndex=28|IndexInSheet=34|OwnerPartId=-1|Location.X=454|Location.Y=512|Color=8388608|FontID=1|IsHidden=T|Text=63mW|Name=Max Power Dissipation
|RECORD=41|OwnerIndex=28|IndexInSheet=35|OwnerPartId=-1|Location.X=454|Location.Y=512|Color=8388608|FontID=1|IsHidden=T|Text=0402|Name=Case/Package
|RECORD=41|OwnerIndex=28|IndexInSheet=36|OwnerPartId=-1|Location.X=454|Location.Y=512|Color=8388608|FontID=1|IsHidden=T|Text=0402|Name=Case Code (Imperial)
|RECORD=41|OwnerIndex=28|IndexInSheet=37|OwnerPartId=-1|Location.X=454|Location.Y=512|Color=8388608|FontID=1|IsHidden=T|Text=RMCF|Name=Series
|RECORD=34|OwnerIndex=28|IndexInSheet=-1|OwnerPartId=-1|Location.X=466|Location.Y=484|Color=8388608|FontID=1|Text=R10|Name=Designator|ReadOnlyState=1
|RECORD=41|OwnerIndex=28|IndexInSheet=-1|OwnerPartId=1|Location.X=466|Location.Y=474|Color=8388608|FontID=1|Text=1k|Name=Comment
|RECORD=44|OwnerIndex=28
|RECORD=45|OwnerIndex=71|IndexInSheet=-1|UseComponentLibrary=T|ModelName=FP-RMCF0402-MFG|ModelType=PCBLIB|DatafileCount=1|ModelDatafileEntity0=FP-RMCF0402-MFG|ModelDatafileKind0=PCBLib|IsCurrent=T|DatalinksLocked=T|DatabaseDatalinksLocked=T
|RECORD=46|OwnerIndex=72
|RECORD=48|OwnerIndex=72
|RECORD=45|OwnerIndex=71|IndexInSheet=-1|UseComponentLibrary=T|ModelName=FP-RMCF0402-IPC_C|ModelType=PCBLIB|DatafileCount=1|ModelDatafileEntity0=FP-RMCF0402-IPC_C|ModelDatafileKind0=PCBLib|DatalinksLocked=T|DatabaseDatalinksLocked=T
|RECORD=46|OwnerIndex=75
|RECORD=48|OwnerIndex=75
|RECORD=45|OwnerIndex=71|IndexInSheet=-1|UseComponentLibrary=T|ModelName=FP-RMCF0402-IPC_B|ModelType=PCBLIB|DatafileCount=1|ModelDatafileEntity0=FP-RMCF0402-IPC_B|ModelDatafileKind0=PCBLib|DatalinksLocked=T|DatabaseDatalinksLocked=T
|RECORD=46|OwnerIndex=78
|RECORD=48|OwnerIndex=78
|RECORD=45|OwnerIndex=71|IndexInSheet=-1|UseComponentLibrary=T|ModelName=FP-RMCF0402-IPC_A|ModelType=PCBLIB|DatafileCount=1|ModelDatafileEntity0=FP-RMCF0402-IPC_A|ModelDatafileKind0=PCBLib|DatalinksLocked=T|DatabaseDatalinksLocked=T
|RECORD=46|OwnerIndex=81
|RECORD=48|OwnerIndex=81
|RECORD=1|LibReference=1029c3af85768c4190bb7ad29bc67b5|ComponentDescription=100kO ±1% 0.063W 0402 Thick Film Chip Resistor AEC-Q200 compliant|PartCount=2|DisplayModeCount=1|IndexInSheet=28|OwnerPartId=-1|Location.X=460|Location.Y=330|Orientation=1|CurrentPartId=1|LibraryPath=*|SourceLibraryName=Altium Content Vault|TargetFileName=*|AreaColor=11599871|Color=128|PartIDLocked=T|DesignItemId=CMP-2000-06984-2|AllPinCount=2
|RECORD=2|OwnerIndex=84|OwnerPartId=1|Electrical=4|PinConglomerate=35|PinLength=20|Location.X=460|Location.Y=350|Name=1|Designator=1|PinPropagationDelay=0.000000E+000
|RECORD=2|OwnerIndex=84|OwnerPartId=1|Electrical=4|PinConglomerate=33|PinLength=20|Location.X=460|Location.Y=380|Name=2|Designator=2|PinPropagationDelay=0.000000E+000
|RECORD=13|OwnerIndex=84|IsNotAccesible=T|IndexInSheet=2|OwnerPartId=1|Location.X=460|Location.Y=350|Corner.X=455|Corner.Y=353|LineWidth=1|Color=16711680
|RECORD=13|OwnerIndex=84|IsNotAccesible=T|IndexInSheet=3|OwnerPartId=1|Location.X=455|Location.Y=353|Corner.X=465|Corner.Y=358|LineWidth=1|Color=16711680
|RECORD=13|OwnerIndex=84|IsNotAccesible=T|IndexInSheet=4|OwnerPartId=1|Location.X=465|Location.Y=358|Corner.X=455|Corner.Y=363|LineWidth=1|Color=16711680
|RECORD=13|OwnerIndex=84|IsNotAccesible=T|IndexInSheet=5|OwnerPartId=1|Location.X=455|Location.Y=363|Corner.X=465|Corner.Y=368|LineWidth=1|Color=16711680
|RECORD=13|OwnerIndex=84|IsNotAccesible=T|IndexInSheet=6|OwnerPartId=1|Location.X=465|Location.Y=368|Corner.X=455|Corner.Y=373|LineWidth=1|Color=16711680
|RECORD=13|OwnerIndex=84|IsNotAccesible=T|IndexInSheet=7|OwnerPartId=1|Location.X=455|Location.Y=373|Corner.X=465|Corner.Y=378|LineWidth=1|Color=16711680
|RECORD=13|OwnerIndex=84|IsNotAccesible=T|IndexInSheet=8|OwnerPartId=1|Location.X=465|Location.Y=378|Corner.X=460|Corner.Y=380|LineWidth=1|Color=16711680
|RECORD=13|OwnerIndex=84|IsNotAccesible=T|IndexInSheet=9|OwnerPartId=1|Location.X=460|Location.Y=350|Corner.X=460|Corner.Y=347|LineWidth=1|Color=16711680
|RECORD=13|OwnerIndex=84|IsNotAccesible=T|IndexInSheet=10|OwnerPartId=1|Location.X=460|Location.Y=380|Corner.X=460|Corner.Y=383|LineWidth=1|Color=16711680
|RECORD=41|OwnerIndex=84|IndexInSheet=11|OwnerPartId=-1|Location.X=454|Location.Y=402|Color=8388608|FontID=1|IsHidden=T|Text=63mW|Name=Max Power Dissipation
|RECORD=41|OwnerIndex=84|IndexInSheet=12|OwnerPartId=-1|Location.X=454|Location.Y=402|Color=8388608|FontID=1|IsHidden=T|Text=Tape and Reel|Name=Packaging
|RECORD=41|OwnerIndex=84|IndexInSheet=13|OwnerPartId=-1|Location.X=454|Location.Y=402|Color=8388608|FontID=1|IsHidden=T|Text=0402|Name=Size Code
|RECORD=41|OwnerIndex=84|IndexInSheet=14|OwnerPartId=-1|Location.X=454|Location.Y=402|Color=8388608|FontID=1|IsHidden=T|Text=100kR|Name=Resistance
|RECORD=41|OwnerIndex=84|IndexInSheet=15|OwnerPartId=-1|Location.X=454|Location.Y=402|Color=8388608|FontID=1|IsHidden=T|Text=Thick Film|Name=Resistor Type
|RECORD=41|OwnerIndex=84|IndexInSheet=16|OwnerPartId=-1|Location.X=454|Location.Y=402|Color=8388608|FontID=1|IsHidden=T|Text=Automotive AEC-Q200|Name=Features
|RECORD=41|OwnerIndex=84|IndexInSheet=17|OwnerPartId=-1|Location.X=454|Location.Y=402|Color=8388608|FontID=1|IsHidden=T|Text=100ppm/°C|Name=Temperature Coefficient
|RECORD=41|OwnerIndex=84|IndexInSheet=18|OwnerPartId=-1|Location.X=454|Location.Y=402|Color=8388608|FontID=1|IsHidden=T|Text=1005|Name=Case Code (Metric)
|RECORD=41|OwnerIndex=84|IndexInSheet=19|OwnerPartId=-1|Location.X=454|Location.Y=402|Color=8388608|FontID=1|IsHidden=T|Text=Yes|Name=RoHS Compliant
|RECORD=41|OwnerIndex=84|IndexInSheet=20|OwnerPartId=-1|Location.X=454|Location.Y=402|Color=8388608|FontID=1|IsHidden=T|Text=1mm|Name=Length
|RECORD=41|OwnerIndex=84|IndexInSheet=21|OwnerPartId=-1|Location.X=454|Location.Y=402|Color=8388608|FontID=1|IsHidden=T|Text=No|Name=Radiation Hardening
|RECORD=41|OwnerIndex=84|IndexInSheet=22|OwnerPartId=-1|Location.X=454|Location.Y=402|Color=8388608|FontID=1|IsHidden=T|Text=Not|Name=Military Standard
|RECORD=41|OwnerIndex=84|IndexInSheet=23|OwnerPartId=-1|Location.X=454|Location.Y=402|Color=8388608|FontID=1|IsHidden=T|Text=0402|Name=Case Code (Imperial)
|RECORD=41|OwnerIndex=84|IndexInSheet=24|OwnerPartId=-1|Location.X=454|Location.Y=402|Color=8388608|FontID=1|IsHidden=T|Text=0.5mm|Name=Depth
|RECORD=41|OwnerIndex=84|IndexInSheet=25|OwnerPartId=-1|Location.X=454|Location.Y=402|Color=8388608|FontID=1|IsHidden=T|Text=155°C|Name=Max Operating Temperature
|RECORD=41|OwnerIndex=84|IndexInSheet=26|OwnerPartId=-1|Location.X=454|Location.Y=402|Color=8388608|FontID=1|IsHidden=T|Text=Lead Free|Name=Lead Free
|RECORD=41|OwnerIndex=84|IndexInSheet=27|OwnerPartId=-1|Location.X=454|Location.Y=402|Color=8388608|FontID=1|IsHidden=T|Text=0402|Name=Case/Package
|RECORD=41|OwnerIndex=84|IndexInSheet=28|OwnerPartId=-1|Location.X=454|Location.Y=402|Color=8388608|FontID=1|IsHidden=T|Text=1%|Name=Tolerance
|RECORD=41|OwnerIndex=84|IndexInSheet=29|OwnerPartId=-1|Location.X=454|Location.Y=402|Color=8388608|FontID=1|IsHidden=T|Text=Rectangular|Name=Construction
|RECORD=41|OwnerIndex=84|IndexInSheet=30|OwnerPartId=-1|Location.X=454|Location.Y=402|Color=8388608|FontID=1|IsHidden=T|Text=2|Name=Number of Terminations
|RECORD=41|OwnerIndex=84|IndexInSheet=31|OwnerPartId=-1|Location.X=454|Location.Y=402|Color=8388608|FontID=1|IsHidden=T|Text=Surface Mount|Name=Mount
|RECORD=41|OwnerIndex=84|IndexInSheet=32|OwnerPartId=-1|Location.X=454|Location.Y=402|Color=8388608|FontID=1|IsHidden=T|Text=-55°C|Name=Min Operating Temperature
|RECORD=41|OwnerIndex=84|IndexInSheet=33|OwnerPartId=-1|Location.X=454|Location.Y=402|Color=8388608|FontID=1|IsHidden=T|Text=0.02inch|Name=Width
|RECORD=41|OwnerIndex=84|IndexInSheet=34|OwnerPartId=-1|Location.X=454|Location.Y=402|Color=8388608|FontID=1|IsHidden=T|Text=RMCF|Name=Series
|RECORD=41|OwnerIndex=84|IndexInSheet=35|OwnerPartId=-1|Location.X=454|Location.Y=402|Color=8388608|FontID=1|IsHidden=T|Text=Tin|Name=Contact Plating
|RECORD=41|OwnerIndex=84|IndexInSheet=36|OwnerPartId=-1|Location.X=454|Location.Y=402|Color=8388608|FontID=1|IsHidden=T|Text=62.5mW|Name=Power Rating
|RECORD=41|OwnerIndex=84|IndexInSheet=37|OwnerPartId=-1|Location.X=454|Location.Y=402|Color=8388608|FontID=1|IsHidden=T|Text=0.016inch|Name=Height
|RECORD=34|OwnerIndex=84|IndexInSheet=-1|OwnerPartId=-1|Location.X=466|Location.Y=374|Color=8388608|FontID=1|Text=R11|Name=Designator|ReadOnlyState=1
|RECORD=41|OwnerIndex=84|IndexInSheet=-1|OwnerPartId=1|Location.X=466|Location.Y=364|Color=8388608|FontID=1|Text=100k|Name=Comment
|RECORD=44|OwnerIndex=84
|RECORD=45|OwnerIndex=127|IndexInSheet=-1|UseComponentLibrary=T|ModelName=FP-RMCF0402-IPC_C|ModelType=PCBLIB|DatafileCount=1|ModelDatafileEntity0=FP-RMCF0402-IPC_C|ModelDatafileKind0=PCBLib|IsCurrent=T|DatalinksLocked=T|DatabaseDatalinksLocked=T
|RECORD=46|OwnerIndex=128
|RECORD=48|OwnerIndex=128
|RECORD=45|OwnerIndex=127|IndexInSheet=-1|UseComponentLibrary=T|ModelName=FP-RMCF0402-IPC_A|ModelType=PCBLIB|DatafileCount=1|ModelDatafileEntity0=FP-RMCF0402-IPC_A|ModelDatafileKind0=PCBLib|DatalinksLocked=T|DatabaseDatalinksLocked=T
|RECORD=46|OwnerIndex=131
|RECORD=48|OwnerIndex=131
|RECORD=45|OwnerIndex=127|IndexInSheet=-1|UseComponentLibrary=T|ModelName=FP-RMCF0402-IPC_B|ModelType=PCBLIB|DatafileCount=1|ModelDatafileEntity0=FP-RMCF0402-IPC_B|ModelDatafileKind0=PCBLib|DatalinksLocked=T|DatabaseDatalinksLocked=T
|RECORD=46|OwnerIndex=134
|RECORD=48|OwnerIndex=134
|RECORD=45|OwnerIndex=127|IndexInSheet=-1|UseComponentLibrary=T|ModelName=FP-RMCF0402-MFG|ModelType=PCBLIB|DatafileCount=1|ModelDatafileEntity0=FP-RMCF0402-MFG|ModelDatafileKind0=PCBLib|DatalinksLocked=T|DatabaseDatalinksLocked=T
|RECORD=46|OwnerIndex=137
|RECORD=48|OwnerIndex=137
|RECORD=1|LibReference=4cc4b267dca4c8e51f7102f422741d8|ComponentDescription=Multilayer type RF Inductor 47nH ±5% 0.72O 300mA 0402|PartCount=2|DisplayModeCount=1|IndexInSheet=29|OwnerPartId=-1|Location.X=350|Location.Y=300|IsMirrored=T|CurrentPartId=1|LibraryPath=*|SourceLibraryName=Altium Content Vault|TargetFileName=*|AreaColor=11599871|Color=128|PartIDLocked=T|DesignItemId=CMP-06042-015783-1|AllPinCount=2
|RECORD=12|OwnerIndex=140|IsNotAccesible=T|OwnerPartId=1|Location.X=340|Location.Y=300|Radius=5|LineWidth=1|EndAngle=180.000|Color=16711680
|RECORD=12|OwnerIndex=140|IsNotAccesible=T|IndexInSheet=1|OwnerPartId=1|Location.X=330|Location.Y=300|Radius=5|LineWidth=1|EndAngle=180.000|Color=16711680
|RECORD=12|OwnerIndex=140|IsNotAccesible=T|IndexInSheet=2|OwnerPartId=1|Location.X=320|Location.Y=300|Radius=5|LineWidth=1|EndAngle=180.000|Color=16711680
|RECORD=8|OwnerIndex=140|IsNotAccesible=T|IndexInSheet=3|OwnerPartId=1|Location.X=340|Location.Y=300|Radius=1|SecondaryRadius=1|LineWidth=1|Color=16711680
|RECORD=2|OwnerIndex=140|OwnerPartId=1|Electrical=4|PinConglomerate=32|PinLength=5|Location.X=345|Location.Y=300|Name=1|Designator=1|PinPropagationDelay=0.000000E+000
|RECORD=2|OwnerIndex=140|OwnerPartId=1|Electrical=4|PinConglomerate=34|PinLength=5|Location.X=315|Location.Y=300|Name=2|Designator=2|PinPropagationDelay=0.000000E+000
|RECORD=41|OwnerIndex=140|IndexInSheet=6|OwnerPartId=-1|Location.X=308|Location.Y=305|Color=8388608|FontID=1|IsHidden=T|Text=5%|Name=Tolerance|IsMirrored=T
|RECORD=41|OwnerIndex=140|IndexInSheet=7|OwnerPartId=-1|Location.X=308|Location.Y=305|Color=8388608|FontID=1|IsHidden=T|Text=Tape and Reel|Name=Packaging|IsMirrored=T
|RECORD=41|OwnerIndex=140|IndexInSheet=8|OwnerPartId=-1|Location.X=308|Location.Y=305|Color=8388608|FontID=1|IsHidden=T|Text=0402|Name=Case Code (Imperial)|IsMirrored=T
|RECORD=41|OwnerIndex=140|IndexInSheet=9|OwnerPartId=-1|Location.X=308|Location.Y=305|Color=8388608|FontID=1|IsHidden=T|Text=125°C|Name=Max Operating Temperature|IsMirrored=T
|RECORD=41|OwnerIndex=140|IndexInSheet=10|OwnerPartId=-1|Location.X=308|Location.Y=305|Color=8388608|FontID=1|IsHidden=T|Text=Not|Name=Military Standard|IsMirrored=T
|RECORD=41|OwnerIndex=140|IndexInSheet=11|OwnerPartId=-1|Location.X=308|Location.Y=305|Color=8388608|FontID=1|IsHidden=T|Text=Air|Name=Core Material|IsMirrored=T
|RECORD=41|OwnerIndex=140|IndexInSheet=12|OwnerPartId=-1|Location.X=308|Location.Y=305|Color=8388608|FontID=1|IsHidden=T|Text=720mR|Name=DC Resistance (DCR)|IsMirrored=T
|RECORD=41|OwnerIndex=140|IndexInSheet=13|OwnerPartId=-1|Location.X=308|Location.Y=305|Color=8388608|FontID=1|IsHidden=T|Text=1mm|Name=Length|IsMirrored=T
|RECORD=41|OwnerIndex=140|IndexInSheet=14|OwnerPartId=-1|Location.X=308|Location.Y=305|Color=8388608|FontID=1|IsHidden=T|Text=No|Name=Radiation Hardening|IsMirrored=T
|RECORD=41|OwnerIndex=140|IndexInSheet=15|OwnerPartId=-1|Location.X=308|Location.Y=305|Color=8388608|FontID=1|IsHidden=T|Text=0.5mm|Name=Height|IsMirrored=T
|RECORD=41|OwnerIndex=140|IndexInSheet=16|OwnerPartId=-1|Location.X=308|Location.Y=305|Color=8388608|FontID=1|IsHidden=T|Text=-55°C|Name=Min Operating Temperature|IsMirrored=T
|RECORD=41|OwnerIndex=140|IndexInSheet=17|OwnerPartId=-1|Location.X=308|Location.Y=305|Color=8388608|FontID=1|IsHidden=T|Text=0.02inch|Name=Width|IsMirrored=T
|RECORD=41|OwnerIndex=140|IndexInSheet=18|OwnerPartId=-1|Location.X=308|Location.Y=305|Color=8388608|FontID=1|IsHidden=T|Text=47nH|Name=Inductance|IsMirrored=T
|RECORD=41|OwnerIndex=140|IndexInSheet=19|OwnerPartId=-1|Location.X=308|Location.Y=305|Color=8388608|FontID=1|IsHidden=T|Text=Lead Free|Name=Lead Free|IsMirrored=T
|RECORD=41|OwnerIndex=140|IndexInSheet=20|OwnerPartId=-1|Location.X=308|Location.Y=305|Color=8388608|FontID=1|IsHidden=T|Text=SMD/SMT|Name=Termination|IsMirrored=T
|RECORD=41|OwnerIndex=140|IndexInSheet=21|OwnerPartId=-1|Location.X=308|Location.Y=305|Color=8388608|FontID=1|IsHidden=T|Text=200mA|Name=DC Current|IsMirrored=T
|RECORD=41|OwnerIndex=140|IndexInSheet=22|OwnerPartId=-1|Location.X=308|Location.Y=305|Color=8388608|FontID=1|IsHidden=T|Text=0.022inch|Name=Height - Seated (Max)|IsMirrored=T
|RECORD=41|OwnerIndex=140|IndexInSheet=23|OwnerPartId=-1|Location.X=308|Location.Y=305|Color=8388608|FontID=1|IsHidden=T|Text=Unshielded|Name=Shielding|IsMirrored=T
|RECORD=41|OwnerIndex=140|IndexInSheet=24|OwnerPartId=-1|Location.X=308|Location.Y=305|Color=8388608|FontID=1|IsHidden=T|Text=1GHz|Name=Self Resonant Frequency|IsMirrored=T
|RECORD=41|OwnerIndex=140|IndexInSheet=25|OwnerPartId=-1|Location.X=308|Location.Y=305|Color=8388608|FontID=1|IsHidden=T|Text=8|Name=Q Factor|IsMirrored=T
|RECORD=41|OwnerIndex=140|IndexInSheet=26|OwnerPartId=-1|Location.X=308|Location.Y=305|Color=8388608|FontID=1|IsHidden=T|Text=200mA|Name=Rated Current-Max|IsMirrored=T
|RECORD=41|OwnerIndex=140|IndexInSheet=27|OwnerPartId=-1|Location.X=308|Location.Y=305|Color=8388608|FontID=1|IsHidden=T|Text=0402|Name=Case/Package|IsMirrored=T
|RECORD=41|OwnerIndex=140|IndexInSheet=28|OwnerPartId=-1|Location.X=308|Location.Y=305|Color=8388608|FontID=1|IsHidden=T|Text=100MHz|Name=Test Frequency|IsMirrored=T
|RECORD=41|OwnerIndex=140|IndexInSheet=29|OwnerPartId=-1|Location.X=308|Location.Y=305|Color=8388608|FontID=1|IsHidden=T|Text=200mA|Name=Max DC Current|IsMirrored=T
|RECORD=41|OwnerIndex=140|IndexInSheet=30|OwnerPartId=-1|Location.X=308|Location.Y=305|Color=8388608|FontID=1|IsHidden=T|Text=LQG15HS|Name=Series|IsMirrored=T
|RECORD=41|OwnerIndex=140|IndexInSheet=31|OwnerPartId=-1|Location.X=308|Location.Y=305|Color=8388608|FontID=1|IsHidden=T|Text=1005|Name=Case Code (Metric)|IsMirrored=T
|RECORD=41|OwnerIndex=140|IndexInSheet=32|OwnerPartId=-1|Location.X=308|Location.Y=305|Color=8388608|FontID=1|IsHidden=T|Text=Surface Mount|Name=Mount|IsMirrored=T
|RECORD=41|OwnerIndex=140|IndexInSheet=33|OwnerPartId=-1|Location.X=308|Location.Y=305|Color=8388608|FontID=1|IsHidden=T|Text=200mA|Name=Current Rating|IsMirrored=T
|RECORD=41|OwnerIndex=140|IndexInSheet=34|OwnerPartId=-1|Location.X=308|Location.Y=305|Color=8388608|FontID=1|IsHidden=T|Text=0.55mm|Name=Depth|IsMirrored=T
|RECORD=41|OwnerIndex=140|IndexInSheet=35|OwnerPartId=-1|Location.X=308|Location.Y=305|Color=8388608|FontID=1|IsHidden=T|Text=1|Name=Package Quantity|IsMirrored=T
|RECORD=34|OwnerIndex=140|IndexInSheet=-1|OwnerPartId=-1|Location.X=315|Location.Y=305|Color=8388608|FontID=1|Text=L1|Name=Designator|ReadOnlyState=1|IsMirrored=T
|RECORD=41|OwnerIndex=140|IndexInSheet=-1|OwnerPartId=1|Location.X=315|Location.Y=287|Color=8388608|FontID=1|Text=47nH 300mA|Name=Comment|IsMirrored=T
|RECORD=44|OwnerIndex=140
|RECORD=45|OwnerIndex=181|IndexInSheet=-1|UseComponentLibrary=T|ModelName=FP-LQG15HH_02-IPC_B|ModelType=PCBLIB|DatafileCount=1|ModelDatafileEntity0=FP-LQG15HH_02-IPC_B|ModelDatafileKind0=PCBLib|IsCurrent=T|DatalinksLocked=T|DatabaseDatalinksLocked=T
|RECORD=46|OwnerIndex=182
|RECORD=48|OwnerIndex=182
|RECORD=45|OwnerIndex=181|IndexInSheet=-1|UseComponentLibrary=T|ModelName=FP-LQG15HH_02-IPC_A|ModelType=PCBLIB|DatafileCount=1|ModelDatafileEntity0=FP-LQG15HH_02-IPC_A|ModelDatafileKind0=PCBLib|DatalinksLocked=T|DatabaseDatalinksLocked=T
|RECORD=46|OwnerIndex=185
|RECORD=48|OwnerIndex=185
|RECORD=45|OwnerIndex=181|IndexInSheet=-1|UseComponentLibrary=T|ModelName=FP-LQG15HH_02-MFG|ModelType=PCBLIB|DatafileCount=1|ModelDatafileEntity0=FP-LQG15HH_02-MFG|ModelDatafileKind0=PCBLib|DatalinksLocked=T|DatabaseDatalinksLocked=T
|RECORD=46|OwnerIndex=188
|RECORD=48|OwnerIndex=188
|RECORD=45|OwnerIndex=181|IndexInSheet=-1|UseComponentLibrary=T|ModelName=FP-LQG15HH_02-IPC_C|ModelType=PCBLIB|DatafileCount=1|ModelDatafileEntity0=FP-LQG15HH_02-IPC_C|ModelDatafileKind0=PCBLib|DatalinksLocked=T|DatabaseDatalinksLocked=T
|RECORD=46|OwnerIndex=191
|RECORD=48|OwnerIndex=191
|RECORD=1|LibReference=edccc070dd5cba1f9372128faf3915e|ComponentDescription=TVS DIODE 14V 40V 0402|PartCount=2|DisplayModeCount=1|IndexInSheet=30|OwnerPartId=-1|Location.X=290|Location.Y=170|Orientation=1|CurrentPartId=1|LibraryPath=*|SourceLibraryName=Altium Content Vault|TargetFileName=*|AreaColor=11599871|Color=128|PartIDLocked=T|DesignItemId=CMP-08607-000011-1|AllPinCount=2
|RECORD=13|OwnerIndex=194|IsNotAccesible=T|OwnerPartId=1|Location.X=280|Location.Y=200|Corner.X=300|Corner.Y=200|LineWidth=1|Color=16711680
|RECORD=13|OwnerIndex=194|IsNotAccesible=T|IndexInSheet=1|OwnerPartId=1|Location.X=285|Location.Y=220|Corner.X=295|Corner.Y=220|LineWidth=1|Color=16711680
|RECORD=13|OwnerIndex=194|IsNotAccesible=T|IndexInSheet=2|OwnerPartId=1|Location.X=280|Location.Y=200|Corner.X=290|Corner.Y=220|LineWidth=1|Color=16711680
|RECORD=13|OwnerIndex=194|IsNotAccesible=T|IndexInSheet=3|OwnerPartId=1|Location.X=300|Location.Y=200|Corner.X=290|Corner.Y=220|LineWidth=1|Color=16711680
|RECORD=13|OwnerIndex=194|IsNotAccesible=T|IndexInSheet=4|OwnerPartId=1|Location.X=285|Location.Y=220|Corner.X=280|Corner.Y=225|LineWidth=1|Color=16711680
|RECORD=13|OwnerIndex=194|IsNotAccesible=T|IndexInSheet=5|OwnerPartId=1|Location.X=295|Location.Y=220|Corner.X=300|Corner.Y=215|LineWidth=1|Color=16711680
|RECORD=13|OwnerIndex=194|IsNotAccesible=T|IndexInSheet=6|OwnerPartId=1|Location.X=290|Location.Y=220|Corner.X=280|Corner.Y=240|LineWidth=1|Color=16711680
|RECORD=13|OwnerIndex=194|IsNotAccesible=T|IndexInSheet=7|OwnerPartId=1|Location.X=280|Location.Y=240|Corner.X=300|Corner.Y=240|LineWidth=1|Color=16711680
|RECORD=13|OwnerIndex=194|IsNotAccesible=T|IndexInSheet=8|OwnerPartId=1|Location.X=300|Location.Y=240|Corner.X=290|Corner.Y=220|LineWidth=1|Color=16711680
|RECORD=13|OwnerIndex=194|IsNotAccesible=T|IndexInSheet=9|OwnerPartId=1|Location.X=290|Location.Y=200|Corner.X=290|Corner.Y=190|LineWidth=1|Color=16711680
|RECORD=13|OwnerIndex=194|IsNotAccesible=T|IndexInSheet=10|OwnerPartId=1|Location.X=290|Location.Y=240|Corner.X=290|Corner.Y=250|LineWidth=1|Color=16711680
|RECORD=2|OwnerIndex=194|OwnerPartId=1|Electrical=4|PinConglomerate=35|PinLength=20|Location.X=290|Location.Y=190|Name=1|Designator=1|PinPropagationDelay=0.000000E+000
|RECORD=2|OwnerIndex=194|OwnerPartId=1|Electrical=4|PinConglomerate=33|PinLength=20|Location.X=290|Location.Y=250|Name=2|Designator=2|PinPropagationDelay=0.000000E+000
|RECORD=41|OwnerIndex=194|IndexInSheet=13|OwnerPartId=-1|Location.X=279|Location.Y=272|Color=8388608|FontID=1|IsHidden=T|Text=-55°C|Name=Temperature Range Low
|RECORD=41|OwnerIndex=194|IndexInSheet=14|OwnerPartId=-1|Location.X=279|Location.Y=272|Color=8388608|FontID=1|IsHidden=T|Text=Yes|Name=Lead Free
|RECORD=41|OwnerIndex=194|IndexInSheet=15|OwnerPartId=-1|Location.X=279|Location.Y=272|Color=8388608|FontID=1|IsHidden=T|Text=-55°C to +125°C|Name=Temperature
|RECORD=41|OwnerIndex=194|IndexInSheet=16|OwnerPartId=-1|Location.X=279|Location.Y=272|Color=8388608|FontID=1|IsHidden=T|Text=TVS DIODE 14V 40V 0402|Name=Digikey Description
|RECORD=41|OwnerIndex=194|IndexInSheet=17|OwnerPartId=-1|Location.X=279|Location.Y=272|Color=8388608|FontID=1|IsHidden=T|Text=Yes|Name=Automotive
|RECORD=41|OwnerIndex=194|IndexInSheet=18|OwnerPartId=-1|Location.X=279|Location.Y=272|Color=8388608|FontID=1|IsHidden=T|Text=TVS Diodes|Name=Device Class L2
|RECORD=41|OwnerIndex=194|IndexInSheet=19|OwnerPartId=-1|Location.X=279|Location.Y=272|Color=8388608|FontID=1|IsHidden=T|Text=14V|Name=Reverse Standoff Voltage
|RECORD=41|OwnerIndex=194|IndexInSheet=20|OwnerPartId=-1|Location.X=279|Location.Y=272|Color=8388608|FontID=1|IsHidden=T|Text=Circuit Protection|Name=Device Class L1
|RECORD=41|OwnerIndex=194|IndexInSheet=21|OwnerPartId=-1|Location.X=279|Location.Y=272|Color=8388608|FontID=1|IsHidden=T|Text=DIOC10050X33|Name=Ipc Land Pattern Name
|RECORD=41|OwnerIndex=194|IndexInSheet=22|OwnerPartId=-1|Location.X=279|Location.Y=272|Color=8388608|FontID=1|IsHidden=T|Text=Grade 1|Name=Automotive Grade
|RECORD=41|OwnerIndex=194|IndexInSheet=23|OwnerPartId=-1|Location.X=279|Location.Y=272|Color=8388608|FontID=1|IsHidden=T|Text=PESD0402-140|Name=Manufacturer Part Number
|RECORD=41|OwnerIndex=194|IndexInSheet=24|OwnerPartId=-1|Location.X=279|Location.Y=272|Color=8388608|FontID=1|IsHidden=T|Text=14V|Name=Breakdown Voltage
|RECORD=41|OwnerIndex=194|IndexInSheet=25|OwnerPartId=-1|Location.X=279|Location.Y=272|Color=8388608|FontID=1|IsHidden=T|Text=0.25pF|Name=Capacitance
|RECORD=41|OwnerIndex=194|IndexInSheet=26|OwnerPartId=-1|Location.X=279|Location.Y=272|Color=8388608|FontID=1|IsHidden=T|Text=0.43mm|Name=Height
|RECORD=41|OwnerIndex=194|IndexInSheet=27|OwnerPartId=-1|Location.X=279|Location.Y=272|Color=8388608|FontID=1|IsHidden=T|Text=40V|Name=Clamping Voltage
|RECORD=41|OwnerIndex=194|IndexInSheet=28|OwnerPartId=-1|Location.X=279|Location.Y=272|Color=8388608|FontID=1|IsHidden=T|Text=0.25pF|Name=Value
|RECORD=41|OwnerIndex=194|IndexInSheet=29|OwnerPartId=-1|Location.X=279|Location.Y=272|Color=8388608|FontID=1|IsHidden=T|Text=TRUE|Name=RoHS
|RECORD=41|OwnerIndex=194|IndexInSheet=30|OwnerPartId=-1|Location.X=279|Location.Y=272|Color=8388608|FontID=1|IsHidden=T|Text=+125°C|Name=Temperature Range High
|RECORD=41|OwnerIndex=194|IndexInSheet=31|OwnerPartId=-1|Location.X=279|Location.Y=272|Color=8388608|FontID=1|IsHidden=T|Text=unset|Name=Device Class L3
|RECORD=41|OwnerIndex=194|IndexInSheet=32|OwnerPartId=-1|Location.X=279|Location.Y=272|Color=8388608|FontID=3|IsHidden=T|Text=https://octopart.com/pesd0402-140-littelfuse-74215061|Name=Octopart
|RECORD=41|OwnerIndex=194|IndexInSheet=33|OwnerPartId=-1|Location.X=279|Location.Y=272|Color=8388608|FontID=1|IsHidden=T|Text=PESD0402|Name=Package
|RECORD=41|OwnerIndex=194|IndexInSheet=34|OwnerPartId=-1|Location.X=279|Location.Y=272|Color=8388608|FontID=3|IsHidden=T|Text=https://www.littelfuse.com/~/media/electronics/datasheets/polymer_esd_suppressors/littelfuse_polymer_esd_suppressor_pesd_catalog_datasheet.pdf.pdf|Name=ComponentLink2URL
|RECORD=41|OwnerIndex=194|IndexInSheet=35|OwnerPartId=-1|Location.X=279|Location.Y=272|Color=8388608|FontID=1|IsHidden=T|Text=Bidirectional|Name=Direction
|RECORD=41|OwnerIndex=194|IndexInSheet=36|OwnerPartId=-1|Location.X=279|Location.Y=272|Color=8388608|FontID=1|IsHidden=T|Text=1|Name=Number Of Channels
|RECORD=41|OwnerIndex=194|IndexInSheet=37|OwnerPartId=-1|Location.X=279|Location.Y=272|Color=8388608|FontID=1|IsHidden=T|Text=Littelfuse Inc.|Name=Manufacturer
|RECORD=41|OwnerIndex=194|IndexInSheet=38|OwnerPartId=-1|Location.X=279|Location.Y=272|Color=8388608|FontID=1|IsHidden=T|Text=Diode|Name=Category
|RECORD=41|OwnerIndex=194|IndexInSheet=39|OwnerPartId=-1|Location.X=279|Location.Y=272|Color=8388608|FontID=1|IsHidden=T|Text=Datasheet|Name=ComponentLink2Description
|RECORD=34|OwnerIndex=194|IndexInSheet=-1|OwnerPartId=-1|Location.X=301|Location.Y=241|Color=8388608|FontID=1|Text=D1|Name=Designator|ReadOnlyState=1
|RECORD=41|OwnerIndex=194|IndexInSheet=-1|OwnerPartId=1|Location.X=301|Location.Y=231|Color=8388608|FontID=1|Text=PESD0402-140|Name=Comment
|RECORD=44|OwnerIndex=194
|RECORD=45|OwnerIndex=239|IndexInSheet=-1|UseComponentLibrary=T|ModelName=FP-PESD0402-MFG|ModelType=PCBLIB|DatafileCount=1|ModelDatafileEntity0=FP-PESD0402-MFG|ModelDatafileKind0=PCBLib|IsCurrent=T|DatalinksLocked=T|DatabaseDatalinksLocked=T
|RECORD=46|OwnerIndex=240
|RECORD=48|OwnerIndex=240
|RECORD=45|OwnerIndex=239|IndexInSheet=-1|UseComponentLibrary=T|ModelName=FP-PESD0402-IPC_C|ModelType=PCBLIB|DatafileCount=1|ModelDatafileEntity0=FP-PESD0402-IPC_C|ModelDatafileKind0=PCBLib|DatalinksLocked=T|DatabaseDatalinksLocked=T
|RECORD=46|OwnerIndex=243
|RECORD=48|OwnerIndex=243
|RECORD=45|OwnerIndex=239|IndexInSheet=-1|UseComponentLibrary=T|ModelName=FP-PESD0402-IPC_B|ModelType=PCBLIB|DatafileCount=1|ModelDatafileEntity0=FP-PESD0402-IPC_B|ModelDatafileKind0=PCBLib|DatalinksLocked=T|DatabaseDatalinksLocked=T
|RECORD=46|OwnerIndex=246
|RECORD=48|OwnerIndex=246
|RECORD=45|OwnerIndex=239|IndexInSheet=-1|UseComponentLibrary=T|ModelName=FP-PESD0402-IPC_A|ModelType=PCBLIB|DatafileCount=1|ModelDatafileEntity0=FP-PESD0402-IPC_A|ModelDatafileKind0=PCBLib|DatalinksLocked=T|DatabaseDatalinksLocked=T
|RECORD=46|OwnerIndex=249
|RECORD=48|OwnerIndex=249
|RECORD=1|LibReference=b4654b650e69147ec39a6b967a45e02|ComponentDescription=Chip Multilayer Ceramic Capacitors for General Purpose, 0201, 10000pF, X7R, 15%, 10%, 16V|PartCount=2|DisplayModeCount=1|IndexInSheet=31|OwnerPartId=-1|Location.X=400|Location.Y=280|CurrentPartId=1|LibraryPath=*|SourceLibraryName=Altium Content Vault|TargetFileName=*|AreaColor=11599871|Color=128|PartIDLocked=T|DesignItemId=CMP-06035-000448-1|AllPinCount=2
|RECORD=2|OwnerIndex=252|OwnerPartId=1|Electrical=4|PinConglomerate=33|PinLength=7|Location.X=400|Location.Y=273|Name=1|Designator=1|PinPropagationDelay=0.000000E+000
|RECORD=2|OwnerIndex=252|OwnerPartId=1|Electrical=4|PinConglomerate=35|PinLength=6|Location.X=400|Location.Y=266|Name=2|Designator=2|PinPropagationDelay=0.000000E+000
|RECORD=13|OwnerIndex=252|IsNotAccesible=T|IndexInSheet=2|OwnerPartId=1|Location.X=410|Location.Y=273|Corner.X=390|Corner.Y=273|LineWidth=1|Color=16711680
|RECORD=13|OwnerIndex=252|IsNotAccesible=T|IndexInSheet=3|OwnerPartId=1|Location.X=410|Location.Y=267|Corner.X=390|Corner.Y=267|LineWidth=1|Color=16711680
|RECORD=13|OwnerIndex=252|IsNotAccesible=T|IndexInSheet=4|OwnerPartId=1|Location.X=400|Location.Y=273|Corner.X=400|Corner.Y=276|LineWidth=1|Color=16711680
|RECORD=13|OwnerIndex=252|IsNotAccesible=T|IndexInSheet=5|OwnerPartId=1|Location.X=400|Location.Y=266|Corner.X=400|Corner.Y=265|LineWidth=1|Color=16711680
|RECORD=41|OwnerIndex=252|IndexInSheet=6|OwnerPartId=-1|Location.X=389|Location.Y=282|Color=8388608|FontID=1|IsHidden=T|Text=300um|Name=Width
|RECORD=41|OwnerIndex=252|IndexInSheet=7|OwnerPartId=-1|Location.X=389|Location.Y=282|Color=8388608|FontID=1|IsHidden=T|Text=10%|Name=Tolerance
|RECORD=41|OwnerIndex=252|IndexInSheet=8|OwnerPartId=-1|Location.X=389|Location.Y=282|Color=8388608|FontID=1|IsHidden=T|Text=10nF|Name=Capacitance
|RECORD=41|OwnerIndex=252|IndexInSheet=9|OwnerPartId=-1|Location.X=389|Location.Y=282|Color=8388608|FontID=1|IsHidden=T|Text=300um|Name=Thickness
|RECORD=41|OwnerIndex=252|IndexInSheet=10|OwnerPartId=-1|Location.X=389|Location.Y=282|Color=8388608|FontID=1|IsHidden=T|Text=X7R|Name=Dielectric
|RECORD=41|OwnerIndex=252|IndexInSheet=11|OwnerPartId=-1|Location.X=389|Location.Y=282|Color=8388608|FontID=1|IsHidden=T|Text=16V|Name=Voltage Rating (DC)
|RECORD=41|OwnerIndex=252|IndexInSheet=12|OwnerPartId=-1|Location.X=389|Location.Y=282|Color=8388608|FontID=1|IsHidden=T|Text=600um|Name=Length
|RECORD=34|OwnerIndex=252|IndexInSheet=-1|OwnerPartId=-1|Location.X=411|Location.Y=267|Color=8388608|FontID=1|Text=C12|Name=Designator|ReadOnlyState=1
|RECORD=41|OwnerIndex=252|IndexInSheet=-1|OwnerPartId=1|Location.X=411|Location.Y=257|Color=8388608|FontID=1|Text=10nF|Name=Comment
|RECORD=44|OwnerIndex=252
|RECORD=45|OwnerIndex=270|IndexInSheet=-1|UseComponentLibrary=T|ModelName=FP-GRM033-0_03-IPC_B|ModelType=PCBLIB|DatafileCount=1|ModelDatafileEntity0=FP-GRM033-0_03-IPC_B|ModelDatafileKind0=PCBLib|IsCurrent=T|DatalinksLocked=T|DatabaseDatalinksLocked=T
|RECORD=46|OwnerIndex=271
|RECORD=48|OwnerIndex=271
|RECORD=45|OwnerIndex=270|IndexInSheet=-1|UseComponentLibrary=T|ModelName=FP-GRM033-0_03-IPC_A|ModelType=PCBLIB|DatafileCount=1|ModelDatafileEntity0=FP-GRM033-0_03-IPC_A|ModelDatafileKind0=PCBLib|DatalinksLocked=T|DatabaseDatalinksLocked=T
|RECORD=46|OwnerIndex=274
|RECORD=48|OwnerIndex=274
|RECORD=45|OwnerIndex=270|IndexInSheet=-1|UseComponentLibrary=T|ModelName=FP-GRM033-0_03-MFG|ModelType=PCBLIB|DatafileCount=1|ModelDatafileEntity0=FP-GRM033-0_03-MFG|ModelDatafileKind0=PCBLib|DatalinksLocked=T|DatabaseDatalinksLocked=T
|RECORD=46|OwnerIndex=277
|RECORD=48|OwnerIndex=277
|RECORD=45|OwnerIndex=270|IndexInSheet=-1|UseComponentLibrary=T|ModelName=FP-GRM033-0_03-IPC_C|ModelType=PCBLIB|DatafileCount=1|ModelDatafileEntity0=FP-GRM033-0_03-IPC_C|ModelDatafileKind0=PCBLib|DatalinksLocked=T|DatabaseDatalinksLocked=T
|RECORD=46|OwnerIndex=280
|RECORD=48|OwnerIndex=280
|RECORD=17|IndexInSheet=32|OwnerPartId=-1|Style=4|ShowNetName=F|Location.X=540|Location.Y=380|Orientation=3|Color=128|FontID=1|Text=GND
|RECORD=17|IndexInSheet=33|OwnerPartId=-1|Style=2|ShowNetName=T|Location.X=540|Location.Y=490|Orientation=1|Color=128|FontID=1|Text=+3V3
|RECORD=1|LibReference=b4654b650e69147ec39a6b967a45e02|ComponentDescription=None|PartCount=2|DisplayModeCount=1|IndexInSheet=34|OwnerPartId=-1|Location.X=560|Location.Y=490|CurrentPartId=1|LibraryPath=*|SourceLibraryName=Altium Content Vault|TargetFileName=*|AreaColor=11599871|Color=128|PartIDLocked=T|DesignItemId=CMP-14477-000330-2|AllPinCount=2
|RECORD=2|OwnerIndex=285|OwnerPartId=1|Electrical=4|PinConglomerate=33|PinLength=7|Location.X=560|Location.Y=483|Name=1|Designator=1|PinPropagationDelay=0.000000E+000
|RECORD=2|OwnerIndex=285|OwnerPartId=1|Electrical=4|PinConglomerate=35|PinLength=6|Location.X=560|Location.Y=476|Name=2|Designator=2|PinPropagationDelay=0.000000E+000
|RECORD=13|OwnerIndex=285|IsNotAccesible=T|IndexInSheet=2|OwnerPartId=1|Location.X=570|Location.Y=483|Corner.X=550|Corner.Y=483|LineWidth=1|Color=16711680
|RECORD=13|OwnerIndex=285|IsNotAccesible=T|IndexInSheet=3|OwnerPartId=1|Location.X=570|Location.Y=477|Corner.X=550|Corner.Y=477|LineWidth=1|Color=16711680
|RECORD=13|OwnerIndex=285|IsNotAccesible=T|IndexInSheet=4|OwnerPartId=1|Location.X=560|Location.Y=483|Corner.X=560|Corner.Y=486|LineWidth=1|Color=16711680
|RECORD=13|OwnerIndex=285|IsNotAccesible=T|IndexInSheet=5|OwnerPartId=1|Location.X=560|Location.Y=476|Corner.X=560|Corner.Y=475|LineWidth=1|Color=16711680
|RECORD=41|OwnerIndex=285|IndexInSheet=6|OwnerPartId=-1|Location.X=549|Location.Y=492|Color=8388608|FontID=1|IsHidden=T|Text=Yes|Name=RoHS Compliant
|RECORD=41|OwnerIndex=285|IndexInSheet=7|OwnerPartId=-1|Location.X=549|Location.Y=492|Color=8388608|FontID=1|IsHidden=T|Text=SMD/SMT|Name=Termination
|RECORD=41|OwnerIndex=285|IndexInSheet=8|OwnerPartId=-1|Location.X=549|Location.Y=492|Color=8388608|FontID=1|IsHidden=T|Text=Tape and Reel|Name=Packaging
|RECORD=41|OwnerIndex=285|IndexInSheet=9|OwnerPartId=-1|Location.X=549|Location.Y=492|Color=8388608|FontID=1|IsHidden=T|Text=50V|Name=Voltage Rating (DC)
|RECORD=41|OwnerIndex=285|IndexInSheet=10|OwnerPartId=-1|Location.X=549|Location.Y=492|Color=8388608|FontID=1|IsHidden=T|Text=100nF|Name=Capacitance
|RECORD=41|OwnerIndex=285|IndexInSheet=11|OwnerPartId=-1|Location.X=549|Location.Y=492|Color=8388608|FontID=1|IsHidden=T|Text=0.5mm|Name=Height
|RECORD=41|OwnerIndex=285|IndexInSheet=12|OwnerPartId=-1|Location.X=549|Location.Y=492|Color=8388608|FontID=1|IsHidden=T|Text=Halogen Free|Name=Halogen Free
|RECORD=41|OwnerIndex=285|IndexInSheet=13|OwnerPartId=-1|Location.X=549|Location.Y=492|Color=8388608|FontID=1|IsHidden=T|Text=1005|Name=Case Code (Metric)
|RECORD=41|OwnerIndex=285|IndexInSheet=14|OwnerPartId=-1|Location.X=549|Location.Y=492|Color=8388608|FontID=1|IsHidden=T|Text=0.02inch|Name=Width
|RECORD=41|OwnerIndex=285|IndexInSheet=15|OwnerPartId=-1|Location.X=549|Location.Y=492|Color=8388608|FontID=1|IsHidden=T|Text=85°C|Name=Max Operating Temperature
|RECORD=41|OwnerIndex=285|IndexInSheet=16|OwnerPartId=-1|Location.X=549|Location.Y=492|Color=8388608|FontID=1|IsHidden=T|Text=50V|Name=Voltage Rating
|RECORD=41|OwnerIndex=285|IndexInSheet=17|OwnerPartId=-1|Location.X=549|Location.Y=492|Color=8388608|FontID=1|IsHidden=T|Text=-55°C|Name=Min Operating Temperature
|RECORD=41|OwnerIndex=285|IndexInSheet=18|OwnerPartId=-1|Location.X=549|Location.Y=492|Color=8388608|FontID=1|IsHidden=T|Text=10000|Name=Package Quantity
|RECORD=41|OwnerIndex=285|IndexInSheet=19|OwnerPartId=-1|Location.X=549|Location.Y=492|Color=8388608|FontID=1|IsHidden=T|Text=0402|Name=Case/Package
|RECORD=41|OwnerIndex=285|IndexInSheet=20|OwnerPartId=-1|Location.X=549|Location.Y=492|Color=8388608|FontID=1|IsHidden=T|Text=0402|Name=Case Code (Imperial)
|RECORD=41|OwnerIndex=285|IndexInSheet=21|OwnerPartId=-1|Location.X=549|Location.Y=492|Color=8388608|FontID=1|IsHidden=T|Text=X5R|Name=Dielectric
|RECORD=41|OwnerIndex=285|IndexInSheet=22|OwnerPartId=-1|Location.X=549|Location.Y=492|Color=8388608|FontID=1|IsHidden=T|Text=10%|Name=Tolerance
|RECORD=41|OwnerIndex=285|IndexInSheet=23|OwnerPartId=-1|Location.X=549|Location.Y=492|Color=8388608|FontID=1|IsHidden=T|Text=0.039inch|Name=Length
|RECORD=41|OwnerIndex=285|IndexInSheet=24|OwnerPartId=-1|Location.X=549|Location.Y=492|Color=8388608|FontID=1|IsHidden=T|Text=0.022inch|Name=Thickness
|RECORD=41|OwnerIndex=285|IndexInSheet=25|OwnerPartId=-1|Location.X=549|Location.Y=492|Color=8388608|FontID=1|IsHidden=T|Text=Surface Mount|Name=Mount
|RECORD=34|OwnerIndex=285|IndexInSheet=-1|OwnerPartId=-1|Location.X=571|Location.Y=477|Color=8388608|FontID=1|Text=C9|Name=Designator|ReadOnlyState=1
|RECORD=41|OwnerIndex=285|IndexInSheet=-1|OwnerPartId=1|Location.X=571|Location.Y=467|Color=8388608|FontID=1|Text=100nF|Name=Comment
|RECORD=44|OwnerIndex=285
|RECORD=45|OwnerIndex=316|IndexInSheet=-1|UseComponentLibrary=T|ModelName=FP-0402-L_1_0_0_05-W_0_5-IPC_B|ModelType=PCBLIB|DatafileCount=1|ModelDatafileEntity0=FP-0402-L_1_0_0_05-W_0_5-IPC_B|ModelDatafileKind0=PCBLib|IsCurrent=T|DatalinksLocked=T|DatabaseDatalinksLocked=T
|RECORD=46|OwnerIndex=317
|RECORD=48|OwnerIndex=317
|RECORD=45|OwnerIndex=316|IndexInSheet=-1|UseComponentLibrary=T|ModelName=FP-0402-L_1_0_0_05-W_0_5-IPC_A|ModelType=PCBLIB|DatafileCount=1|ModelDatafileEntity0=FP-0402-L_1_0_0_05-W_0_5-IPC_A|ModelDatafileKind0=PCBLib|DatalinksLocked=T|DatabaseDatalinksLocked=T
|RECORD=46|OwnerIndex=320
|RECORD=48|OwnerIndex=320
|RECORD=45|OwnerIndex=316|IndexInSheet=-1|UseComponentLibrary=T|ModelName=FP-0402-L_1_0_0_05-W_0_5-MFG|ModelType=PCBLIB|DatafileCount=1|ModelDatafileEntity0=FP-0402-L_1_0_0_05-W_0_5-MFG|ModelDatafileKind0=PCBLib|DatalinksLocked=T|DatabaseDatalinksLocked=T
|RECORD=46|OwnerIndex=323
|RECORD=48|OwnerIndex=323
|RECORD=45|OwnerIndex=316|IndexInSheet=-1|UseComponentLibrary=T|ModelName=UMK105BJ104_V-F|ModelType=SIM|IsCurrent=T|DatalinksLocked=T|DatabaseDatalinksLocked=T
|RECORD=46|OwnerIndex=326
|RECORD=48|OwnerIndex=326
|RECORD=41|OwnerIndex=328|IndexInSheet=-1|OwnerPartId=-1|Color=8388608|FontID=1|IsHidden=T|Text=General|Name=Kind
|RECORD=41|OwnerIndex=328|IndexInSheet=-1|OwnerPartId=-1|Color=8388608|FontID=1|IsHidden=T|Text=Spice Subcircuit|Name=SubKind
|RECORD=41|OwnerIndex=328|IndexInSheet=-1|OwnerPartId=-1|Color=8388608|FontID=1|IsHidden=T|Name=Spice Prefix
|RECORD=41|OwnerIndex=328|IndexInSheet=-1|OwnerPartId=-1|Color=8388608|FontID=1|IsHidden=T|Name=Excluded Parts
|RECORD=41|OwnerIndex=328|IndexInSheet=-1|OwnerPartId=-1|Color=8388608|FontID=1|IsHidden=T|Name=Netlist
|RECORD=41|OwnerIndex=328|IndexInSheet=-1|OwnerPartId=-1|Color=8388608|FontID=1|IsHidden=T|Text=document_sim_cache\ELOCFEDZ\0|Name=SimulationCacheLocation|ReadOnlyState=3
|RECORD=45|OwnerIndex=316|IndexInSheet=-1|UseComponentLibrary=T|ModelName=FP-0402-L_1_0_0_05-W_0_5-IPC_C|ModelType=PCBLIB|DatafileCount=1|ModelDatafileEntity0=FP-0402-L_1_0_0_05-W_0_5-IPC_C|ModelDatafileKind0=PCBLib|DatalinksLocked=T|DatabaseDatalinksLocked=T
|RECORD=46|OwnerIndex=335
|RECORD=48|OwnerIndex=335
|RECORD=17|IndexInSheet=35|OwnerPartId=-1|Style=4|ShowNetName=F|Location.X=560|Location.Y=470|Orientation=3|Color=128|FontID=1|Text=GND
|RECORD=17|IndexInSheet=36|OwnerPartId=-1|Style=4|ShowNetName=F|Location.X=460|Location.Y=330|Orientation=3|Color=128|FontID=1|Text=GND
|RECORD=17|IndexInSheet=37|OwnerPartId=-1|Style=4|ShowNetName=F|Location.X=400|Location.Y=260|Orientation=3|Color=128|FontID=1|Text=GND
|RECORD=1|LibReference=1029c3af85768c4190bb7ad29bc67b5|ComponentDescription=100kO ±1% 0.063W 0402 Thick Film Chip Resistor AEC-Q200 compliant|PartCount=2|DisplayModeCount=1|IndexInSheet=38|OwnerPartId=-1|Location.X=600|Location.Y=610|Orientation=1|CurrentPartId=1|LibraryPath=*|SourceLibraryName=Altium Content Vault|TargetFileName=*|AreaColor=11599871|Color=128|PartIDLocked=T|DesignItemId=CMP-2000-06984-2|AllPinCount=2
|RECORD=2|OwnerIndex=341|OwnerPartId=1|Electrical=4|PinConglomerate=35|PinLength=20|Location.X=600|Location.Y=630|Name=1|Designator=1|PinPropagationDelay=0.000000E+000
|RECORD=2|OwnerIndex=341|OwnerPartId=1|Electrical=4|PinConglomerate=33|PinLength=20|Location.X=600|Location.Y=660|Name=2|Designator=2|PinPropagationDelay=0.000000E+000
|RECORD=13|OwnerIndex=341|IsNotAccesible=T|IndexInSheet=2|OwnerPartId=1|Location.X=600|Location.Y=630|Corner.X=595|Corner.Y=633|LineWidth=1|Color=16711680
|RECORD=13|OwnerIndex=341|IsNotAccesible=T|IndexInSheet=3|OwnerPartId=1|Location.X=595|Location.Y=633|Corner.X=605|Corner.Y=638|LineWidth=1|Color=16711680
|RECORD=13|OwnerIndex=341|IsNotAccesible=T|IndexInSheet=4|OwnerPartId=1|Location.X=605|Location.Y=638|Corner.X=595|Corner.Y=643|LineWidth=1|Color=16711680
|RECORD=13|OwnerIndex=341|IsNotAccesible=T|IndexInSheet=5|OwnerPartId=1|Location.X=595|Location.Y=643|Corner.X=605|Corner.Y=648|LineWidth=1|Color=16711680
|RECORD=13|OwnerIndex=341|IsNotAccesible=T|IndexInSheet=6|OwnerPartId=1|Location.X=605|Location.Y=648|Corner.X=595|Corner.Y=653|LineWidth=1|Color=16711680
|RECORD=13|OwnerIndex=341|IsNotAccesible=T|IndexInSheet=7|OwnerPartId=1|Location.X=595|Location.Y=653|Corner.X=605|Corner.Y=658|LineWidth=1|Color=16711680
|RECORD=13|OwnerIndex=341|IsNotAccesible=T|IndexInSheet=8|OwnerPartId=1|Location.X=605|Location.Y=658|Corner.X=600|Corner.Y=660|LineWidth=1|Color=16711680
|RECORD=13|OwnerIndex=341|IsNotAccesible=T|IndexInSheet=9|OwnerPartId=1|Location.X=600|Location.Y=630|Corner.X=600|Corner.Y=627|LineWidth=1|Color=16711680
|RECORD=13|OwnerIndex=341|IsNotAccesible=T|IndexInSheet=10|OwnerPartId=1|Location.X=600|Location.Y=660|Corner.X=600|Corner.Y=663|LineWidth=1|Color=16711680
|RECORD=41|OwnerIndex=341|IndexInSheet=11|OwnerPartId=-1|Location.X=594|Location.Y=682|Color=8388608|FontID=1|IsHidden=T|Text=63mW|Name=Max Power Dissipation
|RECORD=41|OwnerIndex=341|IndexInSheet=12|OwnerPartId=-1|Location.X=594|Location.Y=682|Color=8388608|FontID=1|IsHidden=T|Text=Tape and Reel|Name=Packaging
|RECORD=41|OwnerIndex=341|IndexInSheet=13|OwnerPartId=-1|Location.X=594|Location.Y=682|Color=8388608|FontID=1|IsHidden=T|Text=0402|Name=Size Code
|RECORD=41|OwnerIndex=341|IndexInSheet=14|OwnerPartId=-1|Location.X=594|Location.Y=682|Color=8388608|FontID=1|IsHidden=T|Text=100kR|Name=Resistance
|RECORD=41|OwnerIndex=341|IndexInSheet=15|OwnerPartId=-1|Location.X=594|Location.Y=682|Color=8388608|FontID=1|IsHidden=T|Text=Thick Film|Name=Resistor Type
|RECORD=41|OwnerIndex=341|IndexInSheet=16|OwnerPartId=-1|Location.X=594|Location.Y=682|Color=8388608|FontID=1|IsHidden=T|Text=Automotive AEC-Q200|Name=Features
|RECORD=41|OwnerIndex=341|IndexInSheet=17|OwnerPartId=-1|Location.X=594|Location.Y=682|Color=8388608|FontID=1|IsHidden=T|Text=100ppm/°C|Name=Temperature Coefficient
|RECORD=41|OwnerIndex=341|IndexInSheet=18|OwnerPartId=-1|Location.X=594|Location.Y=682|Color=8388608|FontID=1|IsHidden=T|Text=1005|Name=Case Code (Metric)
|RECORD=41|OwnerIndex=341|IndexInSheet=19|OwnerPartId=-1|Location.X=594|Location.Y=682|Color=8388608|FontID=1|IsHidden=T|Text=Yes|Name=RoHS Compliant
|RECORD=41|OwnerIndex=341|IndexInSheet=20|OwnerPartId=-1|Location.X=594|Location.Y=682|Color=8388608|FontID=1|IsHidden=T|Text=1mm|Name=Length
|RECORD=41|OwnerIndex=341|IndexInSheet=21|OwnerPartId=-1|Location.X=594|Location.Y=682|Color=8388608|FontID=1|IsHidden=T|Text=No|Name=Radiation Hardening
|RECORD=41|OwnerIndex=341|IndexInSheet=22|OwnerPartId=-1|Location.X=594|Location.Y=682|Color=8388608|FontID=1|IsHidden=T|Text=Not|Name=Military Standard
|RECORD=41|OwnerIndex=341|IndexInSheet=23|OwnerPartId=-1|Location.X=594|Location.Y=682|Color=8388608|FontID=1|IsHidden=T|Text=0402|Name=Case Code (Imperial)
|RECORD=41|OwnerIndex=341|IndexInSheet=24|OwnerPartId=-1|Location.X=594|Location.Y=682|Color=8388608|FontID=1|IsHidden=T|Text=0.5mm|Name=Depth
|RECORD=41|OwnerIndex=341|IndexInSheet=25|OwnerPartId=-1|Location.X=594|Location.Y=682|Color=8388608|FontID=1|IsHidden=T|Text=155°C|Name=Max Operating Temperature
|RECORD=41|OwnerIndex=341|IndexInSheet=26|OwnerPartId=-1|Location.X=594|Location.Y=682|Color=8388608|FontID=1|IsHidden=T|Text=Lead Free|Name=Lead Free
|RECORD=41|OwnerIndex=341|IndexInSheet=27|OwnerPartId=-1|Location.X=594|Location.Y=682|Color=8388608|FontID=1|IsHidden=T|Text=0402|Name=Case/Package
|RECORD=41|OwnerIndex=341|IndexInSheet=28|OwnerPartId=-1|Location.X=594|Location.Y=682|Color=8388608|FontID=1|IsHidden=T|Text=1%|Name=Tolerance
|RECORD=41|OwnerIndex=341|IndexInSheet=29|OwnerPartId=-1|Location.X=594|Location.Y=682|Color=8388608|FontID=1|IsHidden=T|Text=Rectangular|Name=Construction
|RECORD=41|OwnerIndex=341|IndexInSheet=30|OwnerPartId=-1|Location.X=594|Location.Y=682|Color=8388608|FontID=1|IsHidden=T|Text=2|Name=Number of Terminations
|RECORD=41|OwnerIndex=341|IndexInSheet=31|OwnerPartId=-1|Location.X=594|Location.Y=682|Color=8388608|FontID=1|IsHidden=T|Text=Surface Mount|Name=Mount
|RECORD=41|OwnerIndex=341|IndexInSheet=32|OwnerPartId=-1|Location.X=594|Location.Y=682|Color=8388608|FontID=1|IsHidden=T|Text=-55°C|Name=Min Operating Temperature
|RECORD=41|OwnerIndex=341|IndexInSheet=33|OwnerPartId=-1|Location.X=594|Location.Y=682|Color=8388608|FontID=1|IsHidden=T|Text=0.02inch|Name=Width
|RECORD=41|OwnerIndex=341|IndexInSheet=34|OwnerPartId=-1|Location.X=594|Location.Y=682|Color=8388608|FontID=1|IsHidden=T|Text=RMCF|Name=Series
|RECORD=41|OwnerIndex=341|IndexInSheet=35|OwnerPartId=-1|Location.X=594|Location.Y=682|Color=8388608|FontID=1|IsHidden=T|Text=Tin|Name=Contact Plating
|RECORD=41|OwnerIndex=341|IndexInSheet=36|OwnerPartId=-1|Location.X=594|Location.Y=682|Color=8388608|FontID=1|IsHidden=T|Text=62.5mW|Name=Power Rating
|RECORD=41|OwnerIndex=341|IndexInSheet=37|OwnerPartId=-1|Location.X=594|Location.Y=682|Color=8388608|FontID=1|IsHidden=T|Text=0.016inch|Name=Height
|RECORD=34|OwnerIndex=341|IndexInSheet=-1|OwnerPartId=-1|Location.X=606|Location.Y=654|Color=8388608|FontID=1|Text=R9|Name=Designator|ReadOnlyState=1
|RECORD=41|OwnerIndex=341|IndexInSheet=-1|OwnerPartId=1|Location.X=606|Location.Y=644|Color=8388608|FontID=1|Text=100k|Name=Comment
|RECORD=44|OwnerIndex=341
|RECORD=45|OwnerIndex=384|IndexInSheet=-1|UseComponentLibrary=T|ModelName=FP-RMCF0402-IPC_C|ModelType=PCBLIB|DatafileCount=1|ModelDatafileEntity0=FP-RMCF0402-IPC_C|ModelDatafileKind0=PCBLib|IsCurrent=T|DatalinksLocked=T|DatabaseDatalinksLocked=T
|RECORD=46|OwnerIndex=385
|RECORD=48|OwnerIndex=385
|RECORD=45|OwnerIndex=384|IndexInSheet=-1|UseComponentLibrary=T|ModelName=FP-RMCF0402-IPC_A|ModelType=PCBLIB|DatafileCount=1|ModelDatafileEntity0=FP-RMCF0402-IPC_A|ModelDatafileKind0=PCBLib|DatalinksLocked=T|DatabaseDatalinksLocked=T
|RECORD=46|OwnerIndex=388
|RECORD=48|OwnerIndex=388
|RECORD=45|OwnerIndex=384|IndexInSheet=-1|UseComponentLibrary=T|ModelName=FP-RMCF0402-IPC_B|ModelType=PCBLIB|DatafileCount=1|ModelDatafileEntity0=FP-RMCF0402-IPC_B|ModelDatafileKind0=PCBLib|DatalinksLocked=T|DatabaseDatalinksLocked=T
|RECORD=46|OwnerIndex=391
|RECORD=48|OwnerIndex=391
|RECORD=45|OwnerIndex=384|IndexInSheet=-1|UseComponentLibrary=T|ModelName=FP-RMCF0402-MFG|ModelType=PCBLIB|DatafileCount=1|ModelDatafileEntity0=FP-RMCF0402-MFG|ModelDatafileKind0=PCBLib|DatalinksLocked=T|DatabaseDatalinksLocked=T
|RECORD=46|OwnerIndex=394
|RECORD=48|OwnerIndex=394
|RECORD=17|IndexInSheet=39|OwnerPartId=-1|Style=2|ShowNetName=T|Location.X=660|Location.Y=690|Orientation=1|Color=128|FontID=1|Text=+3V3
|RECORD=17|IndexInSheet=40|OwnerPartId=-1|Style=4|ShowNetName=F|Location.X=290|Location.Y=180|Orientation=3|Color=128|FontID=1|Text=GND
|RECORD=1|LibReference=TI-SN74XXX3G0X-XX-8|ComponentDescription=Triple Buffer/Driver With Open-Drain Output, DCU0008A, LARGE T&R|PartCount=5|DisplayModeCount=1|IndexInSheet=41|OwnerPartId=-1|Location.X=750|Location.Y=300|CurrentPartId=4|LibraryPath=*|SourceLibraryName=Altium Content Vault|TargetFileName=*|AreaColor=11599871|Color=128|PartIDLocked=F|DesignItemId=CMP-0859-00615-3|AllPinCount=8
|RECORD=2|OwnerIndex=399|OwnerPartId=3|FormalType=1|Electrical=3|PinConglomerate=48|PinLength=20|Location.X=780|Location.Y=280|Name=3Y|Designator=2|SwapIDPart=Ž&Ž2|PinPropagationDelay=0.000000E+000
|RECORD=2|OwnerIndex=399|OwnerPartId=3|FormalType=1|PinConglomerate=50|PinLength=20|Location.X=750|Location.Y=280|Name=3A|Designator=6|SwapIDPart=Ž&Ž2|PinPropagationDelay=0.000000E+000
|RECORD=13|OwnerIndex=399|IsNotAccesible=T|IndexInSheet=2|OwnerPartId=3|Location.X=750|Location.Y=295|Corner.X=780|Corner.Y=280|LineWidth=1|Color=16711680
|RECORD=13|OwnerIndex=399|IsNotAccesible=T|IndexInSheet=3|OwnerPartId=3|Location.X=750|Location.Y=265|Corner.X=780|Corner.Y=280|LineWidth=1|Color=16711680
|RECORD=13|OwnerIndex=399|IsNotAccesible=T|IndexInSheet=4|OwnerPartId=3|Location.X=750|Location.Y=265|Corner.X=750|Corner.Y=295|LineWidth=1|Color=16711680
|RECORD=2|OwnerIndex=399|OwnerPartId=2|FormalType=1|Electrical=3|PinConglomerate=48|PinLength=20|Location.X=780|Location.Y=280|Name=2Y|Designator=5|SwapIDPart=Ž&Ž2|PinPropagationDelay=0.000000E+000
|RECORD=2|OwnerIndex=399|OwnerPartId=2|FormalType=1|PinConglomerate=50|PinLength=20|Location.X=750|Location.Y=280|Name=2A|Designator=3|SwapIDPart=Ž&Ž2|PinPropagationDelay=0.000000E+000
|RECORD=13|OwnerIndex=399|IsNotAccesible=T|IndexInSheet=7|OwnerPartId=2|Location.X=750|Location.Y=295|Corner.X=780|Corner.Y=280|LineWidth=1|Color=16711680
|RECORD=13|OwnerIndex=399|IsNotAccesible=T|IndexInSheet=8|OwnerPartId=2|Location.X=750|Location.Y=265|Corner.X=780|Corner.Y=280|LineWidth=1|Color=16711680
|RECORD=13|OwnerIndex=399|IsNotAccesible=T|IndexInSheet=9|OwnerPartId=2|Location.X=750|Location.Y=265|Corner.X=750|Corner.Y=295|LineWidth=1|Color=16711680
|RECORD=14|OwnerIndex=399|IsNotAccesible=T|IndexInSheet=10|OwnerPartId=4|Location.X=750|Location.Y=280|Corner.X=810|Corner.Y=300|Color=128|AreaColor=11599871|IsSolid=T
|RECORD=2|OwnerIndex=399|OwnerPartId=4|FormalType=1|Electrical=7|PinConglomerate=56|PinLength=20|Location.X=810|Location.Y=290|Name=GND|Designator=4|PinPropagationDelay=0.000000E+000
|RECORD=2|OwnerIndex=399|OwnerPartId=4|FormalType=1|Electrical=7|PinConglomerate=58|PinLength=20|Location.X=750|Location.Y=290|Name=+3V3|Designator=8|PinPropagationDelay=0.000000E+000
|RECORD=2|OwnerIndex=399|OwnerPartId=1|FormalType=1|Electrical=3|PinConglomerate=48|PinLength=20|Location.X=780|Location.Y=280|Name=1Y|Designator=7|SwapIDPart=Ž&Ž2|PinPropagationDelay=0.000000E+000
|RECORD=2|OwnerIndex=399|OwnerPartId=1|FormalType=1|PinConglomerate=50|PinLength=20|Location.X=750|Location.Y=280|Name=1A|Designator=1|SwapIDPart=Ž&Ž2|PinPropagationDelay=0.000000E+000
|RECORD=13|OwnerIndex=399|IsNotAccesible=T|IndexInSheet=15|OwnerPartId=1|Location.X=750|Location.Y=295|Corner.X=780|Corner.Y=280|LineWidth=1|Color=16711680
|RECORD=13|OwnerIndex=399|IsNotAccesible=T|IndexInSheet=16|OwnerPartId=1|Location.X=750|Location.Y=265|Corner.X=780|Corner.Y=280|LineWidth=1|Color=16711680
|RECORD=13|OwnerIndex=399|IsNotAccesible=T|IndexInSheet=17|OwnerPartId=1|Location.X=750|Location.Y=265|Corner.X=750|Corner.Y=295|LineWidth=1|Color=16711680
|RECORD=41|OwnerIndex=399|IndexInSheet=18|OwnerPartId=-1|Location.X=728|Location.Y=315|Color=8388608|FontID=1|IsHidden=T|Text=SN74LVC3G07|Name=Generic Part Number
|RECORD=41|OwnerIndex=399|IndexInSheet=19|OwnerPartId=-1|Location.X=728|Location.Y=315|Color=8388608|FontID=1|IsHidden=T|Text=5.5|Name=VCC(Max)(V)
|RECORD=41|OwnerIndex=399|IndexInSheet=20|OwnerPartId=-1|Location.X=728|Location.Y=315|Color=8388608|FontID=1|IsHidden=T|Text=Non-Inverting Buffer/Driver|Name=Sub-Family
|RECORD=41|OwnerIndex=399|IndexInSheet=21|OwnerPartId=-1|Location.X=728|Location.Y=315|Color=8388608|FontID=1|IsHidden=T|Text=True|Name=Logic
|RECORD=41|OwnerIndex=399|IndexInSheet=22|OwnerPartId=-1|Location.X=728|Location.Y=315|Color=8388608|FontID=1|IsHidden=T|Text=DCU0008A|Name=PackageReference
|RECORD=41|OwnerIndex=399|IndexInSheet=23|OwnerPartId=-1|Location.X=728|Location.Y=315|Color=8388608|FontID=1|IsHidden=T|Text=8.3,4.8,4.2,3.4|Name=tpd @ Nom Voltage(Max)(ns)
|RECORD=41|OwnerIndex=399|IndexInSheet=24|OwnerPartId=-1|Location.X=728|Location.Y=315|Color=8388608|FontID=1|IsHidden=T|Text=CMOS|Name=Output Type
|RECORD=41|OwnerIndex=399|IndexInSheet=25|OwnerPartId=-1|Location.X=728|Location.Y=315|Color=8388608|FontID=1|IsHidden=T|Text=150|Name=F @ Nom Voltage(Max)(Mhz)
|RECORD=41|OwnerIndex=399|IndexInSheet=26|OwnerPartId=-1|Location.X=728|Location.Y=315|Color=8388608|FontID=1|IsHidden=T|Text=LVC|Name=Technology Family
|RECORD=41|OwnerIndex=399|IndexInSheet=27|OwnerPartId=-1|Location.X=728|Location.Y=315|Color=8388608|FontID=1|IsHidden=T|Text=0.01|Name=ICC @ Nom Voltage(Max)(mA)
|RECORD=41|OwnerIndex=399|IndexInSheet=28|OwnerPartId=-1|Location.X=728|Location.Y=315|Color=8388608|FontID=1|IsHidden=T|Text=1.8,2.5,3.3,5|Name=Voltage(Nom)(V)
|RECORD=41|OwnerIndex=399|IndexInSheet=29|OwnerPartId=-1|Location.X=728|Location.Y=315|Color=8388608|FontID=1|IsHidden=T|Text=No|Name=Schmitt Trigger
|RECORD=41|OwnerIndex=399|IndexInSheet=30|OwnerPartId=-1|Location.X=728|Location.Y=315|Color=8388608|FontID=1|IsHidden=T|Text=Texas Instruments|Name=Manufacturer
|RECORD=41|OwnerIndex=399|IndexInSheet=31|OwnerPartId=-1|Location.X=728|Location.Y=315|Color=8388608|FontID=1|IsHidden=T|Text=1.65|Name=VCC(Min)(V)
|RECORD=41|OwnerIndex=399|IndexInSheet=32|OwnerPartId=-1|Location.X=728|Location.Y=315|Color=8388608|FontID=1|IsHidden=T|Text=No|Name=3-State Output
|RECORD=41|OwnerIndex=399|IndexInSheet=33|OwnerPartId=-1|Location.X=728|Location.Y=315|Color=8388608|FontID=1|IsHidden=T|Text=3|Name=Bits(#)
|RECORD=41|OwnerIndex=399|IndexInSheet=34|OwnerPartId=-1|Location.X=728|Location.Y=315|Color=8388608|FontID=1|IsHidden=T|Text=SCES365K|Name=DatasheetVersion
|RECORD=41|OwnerIndex=399|IndexInSheet=35|OwnerPartId=-1|Location.X=728|Location.Y=315|Color=8388608|FontID=1|IsHidden=T|Text=CMOS/TTL|Name=Input Type
|RECORD=41|OwnerIndex=399|IndexInSheet=36|OwnerPartId=-1|Location.X=728|Location.Y=315|Color=8388608|FontID=1|IsHidden=T|Text=Catalog|Name=Rating
|RECORD=41|OwnerIndex=399|IndexInSheet=37|OwnerPartId=-1|Location.X=728|Location.Y=315|Color=8388608|FontID=1|IsHidden=T|Text=32/-32|Name=Output Drive (IOL/IOH)(Max)(mA)
|RECORD=41|OwnerIndex=399|IndexInSheet=38|OwnerPartId=-1|Location.X=728|Location.Y=315|Color=8388608|FontID=1|IsHidden=T|Text=-40 to 125,-40 to 85|Name=Operating Temperature Range(C)
|RECORD=34|OwnerIndex=399|IndexInSheet=-1|OwnerPartId=-1|Location.X=750|Location.Y=300|Color=8388608|FontID=1|Text=U3|Name=Designator|ReadOnlyState=1
|RECORD=41|OwnerIndex=399|IndexInSheet=-1|OwnerPartId=-1|Location.X=749|Location.Y=254|Color=8388608|FontID=1|Text=SN74LVC3G07DCUR|Name=Comment
|RECORD=44|OwnerIndex=399
|RECORD=45|OwnerIndex=449|IndexInSheet=-1|Description=SOP, 8-Leads, Body 2.4x2.1mm, Pitch 0.5mm, IPC Medium Density|UseComponentLibrary=T|ModelName=DCU0008A_N|ModelType=PCBLIB|DatafileCount=1|ModelDatafileEntity0=DCU0008A_N|ModelDatafileKind0=PCBLib|IsCurrent=T|DatalinksLocked=T|DatabaseDatalinksLocked=T
|RECORD=46|OwnerIndex=450
|RECORD=48|OwnerIndex=450
|RECORD=41|OwnerIndex=452|IndexInSheet=-1|OwnerPartId=-1|Color=8388608|FontID=1|IsHidden=T|Text=2D|Name=Available Preview Images
|RECORD=45|OwnerIndex=449|IndexInSheet=-1|Description=SOP, 8-Leads, Body 2.4x2.1mm, Pitch 0.5mm, IPC Low Density|UseComponentLibrary=T|ModelName=DCU0008A_M|ModelType=PCBLIB|DatafileCount=1|ModelDatafileEntity0=DCU0008A_M|ModelDatafileKind0=PCBLib|DatalinksLocked=T|DatabaseDatalinksLocked=T
|RECORD=46|OwnerIndex=454
|RECORD=48|OwnerIndex=454
|RECORD=41|OwnerIndex=456|IndexInSheet=-1|OwnerPartId=-1|Color=8388608|FontID=1|IsHidden=T|Text=2D|Name=Available Preview Images
|RECORD=45|OwnerIndex=449|IndexInSheet=-1|Description=SOP, 8-Leads, Body 2.4x2.1mm, Pitch 0.5mm, IPC High Density|UseComponentLibrary=T|ModelName=DCU0008A_L|ModelType=PCBLIB|DatafileCount=1|ModelDatafileEntity0=DCU0008A_L|ModelDatafileKind0=PCBLib|DatalinksLocked=T|DatabaseDatalinksLocked=T
|RECORD=46|OwnerIndex=458
|RECORD=48|OwnerIndex=458
|RECORD=41|OwnerIndex=460|IndexInSheet=-1|OwnerPartId=-1|Color=8388608|FontID=1|IsHidden=T|Text=2D|Name=Available Preview Images
|RECORD=1|LibReference=b4654b650e69147ec39a6b967a45e02|ComponentDescription=None|PartCount=2|DisplayModeCount=1|IndexInSheet=42|OwnerPartId=-1|Location.X=700|Location.Y=290|CurrentPartId=1|LibraryPath=*|SourceLibraryName=Altium Content Vault|TargetFileName=*|AreaColor=11599871|Color=128|PartIDLocked=T|DesignItemId=CMP-14477-000330-2|AllPinCount=2
|RECORD=2|OwnerIndex=462|OwnerPartId=1|Electrical=4|PinConglomerate=33|PinLength=7|Location.X=700|Location.Y=283|Name=1|Designator=1|PinPropagationDelay=0.000000E+000
|RECORD=2|OwnerIndex=462|OwnerPartId=1|Electrical=4|PinConglomerate=35|PinLength=6|Location.X=700|Location.Y=276|Name=2|Designator=2|PinPropagationDelay=0.000000E+000
|RECORD=13|OwnerIndex=462|IsNotAccesible=T|IndexInSheet=2|OwnerPartId=1|Location.X=710|Location.Y=283|Corner.X=690|Corner.Y=283|LineWidth=1|Color=16711680
|RECORD=13|OwnerIndex=462|IsNotAccesible=T|IndexInSheet=3|OwnerPartId=1|Location.X=710|Location.Y=277|Corner.X=690|Corner.Y=277|LineWidth=1|Color=16711680
|RECORD=13|OwnerIndex=462|IsNotAccesible=T|IndexInSheet=4|OwnerPartId=1|Location.X=700|Location.Y=283|Corner.X=700|Corner.Y=286|LineWidth=1|Color=16711680
|RECORD=13|OwnerIndex=462|IsNotAccesible=T|IndexInSheet=5|OwnerPartId=1|Location.X=700|Location.Y=276|Corner.X=700|Corner.Y=275|LineWidth=1|Color=16711680
|RECORD=41|OwnerIndex=462|IndexInSheet=6|OwnerPartId=-1|Location.X=689|Location.Y=292|Color=8388608|FontID=1|IsHidden=T|Text=Yes|Name=RoHS Compliant
|RECORD=41|OwnerIndex=462|IndexInSheet=7|OwnerPartId=-1|Location.X=689|Location.Y=292|Color=8388608|FontID=1|IsHidden=T|Text=SMD/SMT|Name=Termination
|RECORD=41|OwnerIndex=462|IndexInSheet=8|OwnerPartId=-1|Location.X=689|Location.Y=292|Color=8388608|FontID=1|IsHidden=T|Text=Tape and Reel|Name=Packaging
|RECORD=41|OwnerIndex=462|IndexInSheet=9|OwnerPartId=-1|Location.X=689|Location.Y=292|Color=8388608|FontID=1|IsHidden=T|Text=50V|Name=Voltage Rating (DC)
|RECORD=41|OwnerIndex=462|IndexInSheet=10|OwnerPartId=-1|Location.X=689|Location.Y=292|Color=8388608|FontID=1|IsHidden=T|Text=100nF|Name=Capacitance
|RECORD=41|OwnerIndex=462|IndexInSheet=11|OwnerPartId=-1|Location.X=689|Location.Y=292|Color=8388608|FontID=1|IsHidden=T|Text=0.5mm|Name=Height
|RECORD=41|OwnerIndex=462|IndexInSheet=12|OwnerPartId=-1|Location.X=689|Location.Y=292|Color=8388608|FontID=1|IsHidden=T|Text=Halogen Free|Name=Halogen Free
|RECORD=41|OwnerIndex=462|IndexInSheet=13|OwnerPartId=-1|Location.X=689|Location.Y=292|Color=8388608|FontID=1|IsHidden=T|Text=1005|Name=Case Code (Metric)
|RECORD=41|OwnerIndex=462|IndexInSheet=14|OwnerPartId=-1|Location.X=689|Location.Y=292|Color=8388608|FontID=1|IsHidden=T|Text=0.02inch|Name=Width
|RECORD=41|OwnerIndex=462|IndexInSheet=15|OwnerPartId=-1|Location.X=689|Location.Y=292|Color=8388608|FontID=1|IsHidden=T|Text=85°C|Name=Max Operating Temperature
|RECORD=41|OwnerIndex=462|IndexInSheet=16|OwnerPartId=-1|Location.X=689|Location.Y=292|Color=8388608|FontID=1|IsHidden=T|Text=50V|Name=Voltage Rating
|RECORD=41|OwnerIndex=462|IndexInSheet=17|OwnerPartId=-1|Location.X=689|Location.Y=292|Color=8388608|FontID=1|IsHidden=T|Text=-55°C|Name=Min Operating Temperature
|RECORD=41|OwnerIndex=462|IndexInSheet=18|OwnerPartId=-1|Location.X=689|Location.Y=292|Color=8388608|FontID=1|IsHidden=T|Text=10000|Name=Package Quantity
|RECORD=41|OwnerIndex=462|IndexInSheet=19|OwnerPartId=-1|Location.X=689|Location.Y=292|Color=8388608|FontID=1|IsHidden=T|Text=0402|Name=Case/Package
|RECORD=41|OwnerIndex=462|IndexInSheet=20|OwnerPartId=-1|Location.X=689|Location.Y=292|Color=8388608|FontID=1|IsHidden=T|Text=0402|Name=Case Code (Imperial)
|RECORD=41|OwnerIndex=462|IndexInSheet=21|OwnerPartId=-1|Location.X=689|Location.Y=292|Color=8388608|FontID=1|IsHidden=T|Text=X5R|Name=Dielectric
|RECORD=41|OwnerIndex=462|IndexInSheet=22|OwnerPartId=-1|Location.X=689|Location.Y=292|Color=8388608|FontID=1|IsHidden=T|Text=10%|Name=Tolerance
|RECORD=41|OwnerIndex=462|IndexInSheet=23|OwnerPartId=-1|Location.X=689|Location.Y=292|Color=8388608|FontID=1|IsHidden=T|Text=0.039inch|Name=Length
|RECORD=41|OwnerIndex=462|IndexInSheet=24|OwnerPartId=-1|Location.X=689|Location.Y=292|Color=8388608|FontID=1|IsHidden=T|Text=0.022inch|Name=Thickness
|RECORD=41|OwnerIndex=462|IndexInSheet=25|OwnerPartId=-1|Location.X=689|Location.Y=292|Color=8388608|FontID=1|IsHidden=T|Text=Surface Mount|Name=Mount
|RECORD=34|OwnerIndex=462|IndexInSheet=-1|OwnerPartId=-1|Location.X=711|Location.Y=277|Color=8388608|FontID=1|Text=C11|Name=Designator|ReadOnlyState=1
|RECORD=41|OwnerIndex=462|IndexInSheet=-1|OwnerPartId=1|Location.X=711|Location.Y=267|Color=8388608|FontID=1|Text=100nF|Name=Comment
|RECORD=44|OwnerIndex=462
|RECORD=45|OwnerIndex=493|IndexInSheet=-1|UseComponentLibrary=T|ModelName=FP-0402-L_1_0_0_05-W_0_5-IPC_B|ModelType=PCBLIB|DatafileCount=1|ModelDatafileEntity0=FP-0402-L_1_0_0_05-W_0_5-IPC_B|ModelDatafileKind0=PCBLib|IsCurrent=T|DatalinksLocked=T|DatabaseDatalinksLocked=T
|RECORD=46|OwnerIndex=494
|RECORD=48|OwnerIndex=494
|RECORD=45|OwnerIndex=493|IndexInSheet=-1|UseComponentLibrary=T|ModelName=FP-0402-L_1_0_0_05-W_0_5-IPC_A|ModelType=PCBLIB|DatafileCount=1|ModelDatafileEntity0=FP-0402-L_1_0_0_05-W_0_5-IPC_A|ModelDatafileKind0=PCBLib|DatalinksLocked=T|DatabaseDatalinksLocked=T
|RECORD=46|OwnerIndex=497
|RECORD=48|OwnerIndex=497
|RECORD=45|OwnerIndex=493|IndexInSheet=-1|UseComponentLibrary=T|ModelName=FP-0402-L_1_0_0_05-W_0_5-MFG|ModelType=PCBLIB|DatafileCount=1|ModelDatafileEntity0=FP-0402-L_1_0_0_05-W_0_5-MFG|ModelDatafileKind0=PCBLib|DatalinksLocked=T|DatabaseDatalinksLocked=T
|RECORD=46|OwnerIndex=500
|RECORD=48|OwnerIndex=500
|RECORD=45|OwnerIndex=493|IndexInSheet=-1|UseComponentLibrary=T|ModelName=UMK105BJ104_V-F|ModelType=SIM|IsCurrent=T|DatalinksLocked=T|DatabaseDatalinksLocked=T
|RECORD=46|OwnerIndex=503
|RECORD=48|OwnerIndex=503
|RECORD=41|OwnerIndex=505|IndexInSheet=-1|OwnerPartId=-1|Color=8388608|FontID=1|IsHidden=T|Text=General|Name=Kind
|RECORD=41|OwnerIndex=505|IndexInSheet=-1|OwnerPartId=-1|Color=8388608|FontID=1|IsHidden=T|Text=Spice Subcircuit|Name=SubKind
|RECORD=41|OwnerIndex=505|IndexInSheet=-1|OwnerPartId=-1|Color=8388608|FontID=1|IsHidden=T|Name=Spice Prefix
|RECORD=41|OwnerIndex=505|IndexInSheet=-1|OwnerPartId=-1|Color=8388608|FontID=1|IsHidden=T|Name=Excluded Parts
|RECORD=41|OwnerIndex=505|IndexInSheet=-1|OwnerPartId=-1|Color=8388608|FontID=1|IsHidden=T|Name=Netlist
|RECORD=41|OwnerIndex=505|IndexInSheet=-1|OwnerPartId=-1|Color=8388608|FontID=1|IsHidden=T|Text=document_sim_cache\ELOCFEDZ\0|Name=SimulationCacheLocation|ReadOnlyState=3
|RECORD=45|OwnerIndex=493|IndexInSheet=-1|UseComponentLibrary=T|ModelName=FP-0402-L_1_0_0_05-W_0_5-IPC_C|ModelType=PCBLIB|DatafileCount=1|ModelDatafileEntity0=FP-0402-L_1_0_0_05-W_0_5-IPC_C|ModelDatafileKind0=PCBLib|DatalinksLocked=T|DatabaseDatalinksLocked=T
|RECORD=46|OwnerIndex=512
|RECORD=48|OwnerIndex=512
|RECORD=17|IndexInSheet=43|OwnerPartId=-1|Style=4|ShowNetName=F|Location.X=700|Location.Y=270|Orientation=3|Color=128|FontID=1|Text=GND
|RECORD=17|IndexInSheet=44|OwnerPartId=-1|Style=2|ShowNetName=T|Location.X=700|Location.Y=290|Orientation=1|Color=128|FontID=1|Text=+3V3
|RECORD=17|IndexInSheet=45|OwnerPartId=-1|Style=4|ShowNetName=F|Location.X=840|Location.Y=290|Orientation=3|Color=128|FontID=1|Text=GND
|RECORD=25|IndexInSheet=46|OwnerPartId=-1|Location.X=680|Location.Y=490|Color=128|FontID=1|Text=ANT_OFF
|RECORD=25|IndexInSheet=47|OwnerPartId=-1|Location.X=870|Location.Y=420|Justification=2|Color=128|FontID=1|Text=ANT_DET
|RECORD=25|IndexInSheet=48|OwnerPartId=-1|Location.X=870|Location.Y=350|Justification=2|Color=128|FontID=1|Text=ANT_SHORT_N
|RECORD=4|IndexInSheet=49|OwnerPartId=-1|Location.X=30|Location.Y=700|Color=8388608|FontID=5|Text=Antenna Supervisor
|RECORD=17|IndexInSheet=50|OwnerPartId=-1|Style=4|ShowNetName=F|Location.X=170|Location.Y=230|Orientation=3|Color=128|FontID=1|Text=GND
|RECORD=25|IndexInSheet=51|OwnerPartId=-1|Location.X=220|Location.Y=370|Color=128|FontID=1|Text=RF_IN
|RECORD=1|LibReference=b4654b650e69147ec39a6b967a45e02|ComponentDescription=None|PartCount=2|DisplayModeCount=1|IndexInSheet=52|OwnerPartId=-1|Location.X=280|Location.Y=360|CurrentPartId=1|LibraryPath=*|SourceLibraryName=Altium Content Vault|TargetFileName=*|AreaColor=11599871|Color=128|PartIDLocked=T|DesignItemId=CMP-14477-000330-2|AllPinCount=2
|RECORD=2|OwnerIndex=524|OwnerPartId=1|Electrical=4|PinConglomerate=33|PinLength=7|Location.X=280|Location.Y=353|Name=1|Designator=1|PinPropagationDelay=0.000000E+000
|RECORD=2|OwnerIndex=524|OwnerPartId=1|Electrical=4|PinConglomerate=35|PinLength=6|Location.X=280|Location.Y=346|Name=2|Designator=2|PinPropagationDelay=0.000000E+000
|RECORD=13|OwnerIndex=524|IsNotAccesible=T|IndexInSheet=2|OwnerPartId=1|Location.X=290|Location.Y=353|Corner.X=270|Corner.Y=353|LineWidth=1|Color=16711680
|RECORD=13|OwnerIndex=524|IsNotAccesible=T|IndexInSheet=3|OwnerPartId=1|Location.X=290|Location.Y=347|Corner.X=270|Corner.Y=347|LineWidth=1|Color=16711680
|RECORD=13|OwnerIndex=524|IsNotAccesible=T|IndexInSheet=4|OwnerPartId=1|Location.X=280|Location.Y=353|Corner.X=280|Corner.Y=356|LineWidth=1|Color=16711680
|RECORD=13|OwnerIndex=524|IsNotAccesible=T|IndexInSheet=5|OwnerPartId=1|Location.X=280|Location.Y=346|Corner.X=280|Corner.Y=345|LineWidth=1|Color=16711680
|RECORD=41|OwnerIndex=524|IndexInSheet=6|OwnerPartId=-1|Location.X=269|Location.Y=362|Color=8388608|FontID=1|IsHidden=T|Text=Yes|Name=RoHS Compliant
|RECORD=41|OwnerIndex=524|IndexInSheet=7|OwnerPartId=-1|Location.X=269|Location.Y=362|Color=8388608|FontID=1|IsHidden=T|Text=SMD/SMT|Name=Termination
|RECORD=41|OwnerIndex=524|IndexInSheet=8|OwnerPartId=-1|Location.X=269|Location.Y=362|Color=8388608|FontID=1|IsHidden=T|Text=Tape and Reel|Name=Packaging
|RECORD=41|OwnerIndex=524|IndexInSheet=9|OwnerPartId=-1|Location.X=269|Location.Y=362|Color=8388608|FontID=1|IsHidden=T|Text=50V|Name=Voltage Rating (DC)
|RECORD=41|OwnerIndex=524|IndexInSheet=10|OwnerPartId=-1|Location.X=269|Location.Y=362|Color=8388608|FontID=1|IsHidden=T|Text=100nF|Name=Capacitance
|RECORD=41|OwnerIndex=524|IndexInSheet=11|OwnerPartId=-1|Location.X=269|Location.Y=362|Color=8388608|FontID=1|IsHidden=T|Text=0.5mm|Name=Height
|RECORD=41|OwnerIndex=524|IndexInSheet=12|OwnerPartId=-1|Location.X=269|Location.Y=362|Color=8388608|FontID=1|IsHidden=T|Text=Halogen Free|Name=Halogen Free
|RECORD=41|OwnerIndex=524|IndexInSheet=13|OwnerPartId=-1|Location.X=269|Location.Y=362|Color=8388608|FontID=1|IsHidden=T|Text=1005|Name=Case Code (Metric)
|RECORD=41|OwnerIndex=524|IndexInSheet=14|OwnerPartId=-1|Location.X=269|Location.Y=362|Color=8388608|FontID=1|IsHidden=T|Text=0.02inch|Name=Width
|RECORD=41|OwnerIndex=524|IndexInSheet=15|OwnerPartId=-1|Location.X=269|Location.Y=362|Color=8388608|FontID=1|IsHidden=T|Text=85°C|Name=Max Operating Temperature
|RECORD=41|OwnerIndex=524|IndexInSheet=16|OwnerPartId=-1|Location.X=269|Location.Y=362|Color=8388608|FontID=1|IsHidden=T|Text=50V|Name=Voltage Rating
|RECORD=41|OwnerIndex=524|IndexInSheet=17|OwnerPartId=-1|Location.X=269|Location.Y=362|Color=8388608|FontID=1|IsHidden=T|Text=-55°C|Name=Min Operating Temperature
|RECORD=41|OwnerIndex=524|IndexInSheet=18|OwnerPartId=-1|Location.X=269|Location.Y=362|Color=8388608|FontID=1|IsHidden=T|Text=10000|Name=Package Quantity
|RECORD=41|OwnerIndex=524|IndexInSheet=19|OwnerPartId=-1|Location.X=269|Location.Y=362|Color=8388608|FontID=1|IsHidden=T|Text=0402|Name=Case/Package
|RECORD=41|OwnerIndex=524|IndexInSheet=20|OwnerPartId=-1|Location.X=269|Location.Y=362|Color=8388608|FontID=1|IsHidden=T|Text=0402|Name=Case Code (Imperial)
|RECORD=41|OwnerIndex=524|IndexInSheet=21|OwnerPartId=-1|Location.X=269|Location.Y=362|Color=8388608|FontID=1|IsHidden=T|Text=X5R|Name=Dielectric
|RECORD=41|OwnerIndex=524|IndexInSheet=22|OwnerPartId=-1|Location.X=269|Location.Y=362|Color=8388608|FontID=1|IsHidden=T|Text=10%|Name=Tolerance
|RECORD=41|OwnerIndex=524|IndexInSheet=23|OwnerPartId=-1|Location.X=269|Location.Y=362|Color=8388608|FontID=1|IsHidden=T|Text=0.039inch|Name=Length
|RECORD=41|OwnerIndex=524|IndexInSheet=24|OwnerPartId=-1|Location.X=269|Location.Y=362|Color=8388608|FontID=1|IsHidden=T|Text=0.022inch|Name=Thickness
|RECORD=41|OwnerIndex=524|IndexInSheet=25|OwnerPartId=-1|Location.X=269|Location.Y=362|Color=8388608|FontID=1|IsHidden=T|Text=Surface Mount|Name=Mount
|RECORD=34|OwnerIndex=524|IndexInSheet=-1|OwnerPartId=-1|Location.X=291|Location.Y=347|Color=8388608|FontID=1|Text=C10|Name=Designator|ReadOnlyState=1
|RECORD=41|OwnerIndex=524|IndexInSheet=-1|OwnerPartId=1|Location.X=291|Location.Y=337|Color=8388608|FontID=1|Text=100nF|Name=Comment
|RECORD=44|OwnerIndex=524
|RECORD=45|OwnerIndex=555|IndexInSheet=-1|UseComponentLibrary=T|ModelName=FP-0402-L_1_0_0_05-W_0_5-IPC_B|ModelType=PCBLIB|DatafileCount=1|ModelDatafileEntity0=FP-0402-L_1_0_0_05-W_0_5-IPC_B|ModelDatafileKind0=PCBLib|IsCurrent=T|DatalinksLocked=T|DatabaseDatalinksLocked=T
|RECORD=46|OwnerIndex=556
|RECORD=48|OwnerIndex=556
|RECORD=45|OwnerIndex=555|IndexInSheet=-1|UseComponentLibrary=T|ModelName=FP-0402-L_1_0_0_05-W_0_5-IPC_A|ModelType=PCBLIB|DatafileCount=1|ModelDatafileEntity0=FP-0402-L_1_0_0_05-W_0_5-IPC_A|ModelDatafileKind0=PCBLib|DatalinksLocked=T|DatabaseDatalinksLocked=T
|RECORD=46|OwnerIndex=559
|RECORD=48|OwnerIndex=559
|RECORD=45|OwnerIndex=555|IndexInSheet=-1|UseComponentLibrary=T|ModelName=FP-0402-L_1_0_0_05-W_0_5-MFG|ModelType=PCBLIB|DatafileCount=1|ModelDatafileEntity0=FP-0402-L_1_0_0_05-W_0_5-MFG|ModelDatafileKind0=PCBLib|DatalinksLocked=T|DatabaseDatalinksLocked=T
|RECORD=46|OwnerIndex=562
|RECORD=48|OwnerIndex=562
|RECORD=45|OwnerIndex=555|IndexInSheet=-1|UseComponentLibrary=T|ModelName=UMK105BJ104_V-F|ModelType=SIM|IsCurrent=T|DatalinksLocked=T|DatabaseDatalinksLocked=T
|RECORD=46|OwnerIndex=565
|RECORD=48|OwnerIndex=565
|RECORD=41|OwnerIndex=567|IndexInSheet=-1|OwnerPartId=-1|Color=8388608|FontID=1|IsHidden=T|Text=General|Name=Kind
|RECORD=41|OwnerIndex=567|IndexInSheet=-1|OwnerPartId=-1|Color=8388608|FontID=1|IsHidden=T|Text=Spice Subcircuit|Name=SubKind
|RECORD=41|OwnerIndex=567|IndexInSheet=-1|OwnerPartId=-1|Color=8388608|FontID=1|IsHidden=T|Name=Spice Prefix
|RECORD=41|OwnerIndex=567|IndexInSheet=-1|OwnerPartId=-1|Color=8388608|FontID=1|IsHidden=T|Name=Excluded Parts
|RECORD=41|OwnerIndex=567|IndexInSheet=-1|OwnerPartId=-1|Color=8388608|FontID=1|IsHidden=T|Name=Netlist
|RECORD=41|OwnerIndex=567|IndexInSheet=-1|OwnerPartId=-1|Color=8388608|FontID=1|IsHidden=T|Text=document_sim_cache\ELOCFEDZ\0|Name=SimulationCacheLocation|ReadOnlyState=3
|RECORD=45|OwnerIndex=555|IndexInSheet=-1|UseComponentLibrary=T|ModelName=FP-0402-L_1_0_0_05-W_0_5-IPC_C|ModelType=PCBLIB|DatafileCount=1|ModelDatafileEntity0=FP-0402-L_1_0_0_05-W_0_5-IPC_C|ModelDatafileKind0=PCBLib|DatalinksLocked=T|DatabaseDatalinksLocked=T
|RECORD=46|OwnerIndex=574
|RECORD=48|OwnerIndex=574
|RECORD=28|IndexInSheet=53|OwnerPartId=-1|Location.X=710|Location.Y=200|Corner.X=840|Corner.Y=230|AreaColor=16777215|FontID=1|IsSolid=T|Alignment=1|WordWrap=T|ClipToRect=T|Text=ANT_OFF (active high): pin is low to enable an external antenna.|TextMargin_Frac=5
|RECORD=28|IndexInSheet=54|OwnerPartId=-1|Location.X=450|Location.Y=590|Corner.X=490|Corner.Y=610|AreaColor=16777215|FontID=1|IsSolid=T|Alignment=1|WordWrap=T|ClipToRect=T|Text=High-side Switch~1|TextMargin_Frac=5
|RECORD=14|IndexInSheet=55|OwnerPartId=-1|Location.X=620|Location.Y=240|Corner.X=880|Corner.Y=530|Color=128|AreaColor=11599871
|RECORD=4|IndexInSheet=56|OwnerPartId=-1|Location.X=670|Location.Y=530|Color=8388608|FontID=4|Text=Buffer
|RECORD=14|IndexInSheet=57|OwnerPartId=-1|Location.X=70|Location.Y=260|Corner.X=370|Corner.Y=420|Color=128|AreaColor=11599871
|RECORD=4|IndexInSheet=58|OwnerPartId=-1|Location.X=150|Location.Y=420|Color=8388608|FontID=4|Text=Bias tee
|RECORD=25|IndexInSheet=59|OwnerPartId=-1|Location.X=220|Location.Y=300|Color=128|FontID=1|Text=RF_ANT
|RECORD=43|IndexInSheet=61|OwnerPartId=-1|Location.X=210|Location.Y=360|Color=255|Orientation=2|Name=RF
|RECORD=41|OwnerIndex=584|OwnerPartId=-1|Location.X=139|Location.X_Frac=58995|Location.Y=344|Color=8388608|FontID=1|IsHidden=T|Text=RF|Name=ClassName
|RECORD=1|LibReference=TI-SN74XXX3G0X-XX-8|ComponentDescription=Triple Buffer/Driver With Open-Drain Output, DCU0008A, LARGE T&R|PartCount=5|DisplayModeCount=1|IndexInSheet=62|OwnerPartId=-1|Location.X=750|Location.Y=510|CurrentPartId=3|LibraryPath=*|SourceLibraryName=Altium Content Vault|TargetFileName=*|AreaColor=11599871|Color=128|PartIDLocked=F|DesignItemId=CMP-0859-00615-3|AllPinCount=8
|RECORD=2|OwnerIndex=586|OwnerPartId=3|FormalType=1|Electrical=3|PinConglomerate=48|PinLength=20|Location.X=780|Location.Y=490|Name=3Y|Designator=2|SwapIDPart=Ž&Ž2|PinPropagationDelay=0.000000E+000
|RECORD=2|OwnerIndex=586|OwnerPartId=3|FormalType=1|PinConglomerate=50|PinLength=20|Location.X=750|Location.Y=490|Name=3A|Designator=6|SwapIDPart=Ž&Ž2|PinPropagationDelay=0.000000E+000
|RECORD=13|OwnerIndex=586|IsNotAccesible=T|IndexInSheet=2|OwnerPartId=3|Location.X=750|Location.Y=505|Corner.X=780|Corner.Y=490|LineWidth=1|Color=16711680
|RECORD=13|OwnerIndex=586|IsNotAccesible=T|IndexInSheet=3|OwnerPartId=3|Location.X=750|Location.Y=475|Corner.X=780|Corner.Y=490|LineWidth=1|Color=16711680
|RECORD=13|OwnerIndex=586|IsNotAccesible=T|IndexInSheet=4|OwnerPartId=3|Location.X=750|Location.Y=475|Corner.X=750|Corner.Y=505|LineWidth=1|Color=16711680
|RECORD=2|OwnerIndex=586|OwnerPartId=2|FormalType=1|Electrical=3|PinConglomerate=48|PinLength=20|Location.X=780|Location.Y=490|Name=2Y|Designator=5|SwapIDPart=Ž&Ž2|PinPropagationDelay=0.000000E+000
|RECORD=2|OwnerIndex=586|OwnerPartId=2|FormalType=1|PinConglomerate=50|PinLength=20|Location.X=750|Location.Y=490|Name=2A|Designator=3|SwapIDPart=Ž&Ž2|PinPropagationDelay=0.000000E+000
|RECORD=13|OwnerIndex=586|IsNotAccesible=T|IndexInSheet=7|OwnerPartId=2|Location.X=750|Location.Y=505|Corner.X=780|Corner.Y=490|LineWidth=1|Color=16711680
|RECORD=13|OwnerIndex=586|IsNotAccesible=T|IndexInSheet=8|OwnerPartId=2|Location.X=750|Location.Y=475|Corner.X=780|Corner.Y=490|LineWidth=1|Color=16711680
|RECORD=13|OwnerIndex=586|IsNotAccesible=T|IndexInSheet=9|OwnerPartId=2|Location.X=750|Location.Y=475|Corner.X=750|Corner.Y=505|LineWidth=1|Color=16711680
|RECORD=14|OwnerIndex=586|IsNotAccesible=T|IndexInSheet=10|OwnerPartId=4|Location.X=750|Location.Y=490|Corner.X=810|Corner.Y=510|Color=128|AreaColor=11599871|IsSolid=T
|RECORD=2|OwnerIndex=586|OwnerPartId=4|FormalType=1|Electrical=7|PinConglomerate=56|PinLength=20|Location.X=810|Location.Y=500|Name=GND|Designator=4|PinPropagationDelay=0.000000E+000
|RECORD=2|OwnerIndex=586|OwnerPartId=4|FormalType=1|Electrical=7|PinConglomerate=58|PinLength=20|Location.X=750|Location.Y=500|Name=VCC|Designator=8|PinPropagationDelay=0.000000E+000
|RECORD=2|OwnerIndex=586|OwnerPartId=1|FormalType=1|Electrical=3|PinConglomerate=48|PinLength=20|Location.X=780|Location.Y=490|Name=1Y|Designator=7|SwapIDPart=Ž&Ž2|PinPropagationDelay=0.000000E+000
|RECORD=2|OwnerIndex=586|OwnerPartId=1|FormalType=1|PinConglomerate=50|PinLength=20|Location.X=750|Location.Y=490|Name=1A|Designator=1|SwapIDPart=Ž&Ž2|PinPropagationDelay=0.000000E+000
|RECORD=13|OwnerIndex=586|IsNotAccesible=T|IndexInSheet=15|OwnerPartId=1|Location.X=750|Location.Y=505|Corner.X=780|Corner.Y=490|LineWidth=1|Color=16711680
|RECORD=13|OwnerIndex=586|IsNotAccesible=T|IndexInSheet=16|OwnerPartId=1|Location.X=750|Location.Y=475|Corner.X=780|Corner.Y=490|LineWidth=1|Color=16711680
|RECORD=13|OwnerIndex=586|IsNotAccesible=T|IndexInSheet=17|OwnerPartId=1|Location.X=750|Location.Y=475|Corner.X=750|Corner.Y=505|LineWidth=1|Color=16711680
|RECORD=41|OwnerIndex=586|IndexInSheet=18|OwnerPartId=-1|Location.X=728|Location.Y=525|Color=8388608|FontID=1|IsHidden=T|Text=SN74LVC3G07|Name=Generic Part Number
|RECORD=41|OwnerIndex=586|IndexInSheet=19|OwnerPartId=-1|Location.X=728|Location.Y=525|Color=8388608|FontID=1|IsHidden=T|Text=5.5|Name=VCC(Max)(V)
|RECORD=41|OwnerIndex=586|IndexInSheet=20|OwnerPartId=-1|Location.X=728|Location.Y=525|Color=8388608|FontID=1|IsHidden=T|Text=Non-Inverting Buffer/Driver|Name=Sub-Family
|RECORD=41|OwnerIndex=586|IndexInSheet=21|OwnerPartId=-1|Location.X=728|Location.Y=525|Color=8388608|FontID=1|IsHidden=T|Text=True|Name=Logic
|RECORD=41|OwnerIndex=586|IndexInSheet=22|OwnerPartId=-1|Location.X=728|Location.Y=525|Color=8388608|FontID=1|IsHidden=T|Text=DCU0008A|Name=PackageReference
|RECORD=41|OwnerIndex=586|IndexInSheet=23|OwnerPartId=-1|Location.X=728|Location.Y=525|Color=8388608|FontID=1|IsHidden=T|Text=8.3,4.8,4.2,3.4|Name=tpd @ Nom Voltage(Max)(ns)
|RECORD=41|OwnerIndex=586|IndexInSheet=24|OwnerPartId=-1|Location.X=728|Location.Y=525|Color=8388608|FontID=1|IsHidden=T|Text=CMOS|Name=Output Type
|RECORD=41|OwnerIndex=586|IndexInSheet=25|OwnerPartId=-1|Location.X=728|Location.Y=525|Color=8388608|FontID=1|IsHidden=T|Text=150|Name=F @ Nom Voltage(Max)(Mhz)
|RECORD=41|OwnerIndex=586|IndexInSheet=26|OwnerPartId=-1|Location.X=728|Location.Y=525|Color=8388608|FontID=1|IsHidden=T|Text=LVC|Name=Technology Family
|RECORD=41|OwnerIndex=586|IndexInSheet=27|OwnerPartId=-1|Location.X=728|Location.Y=525|Color=8388608|FontID=1|IsHidden=T|Text=0.01|Name=ICC @ Nom Voltage(Max)(mA)
|RECORD=41|OwnerIndex=586|IndexInSheet=28|OwnerPartId=-1|Location.X=728|Location.Y=525|Color=8388608|FontID=1|IsHidden=T|Text=1.8,2.5,3.3,5|Name=Voltage(Nom)(V)
|RECORD=41|OwnerIndex=586|IndexInSheet=29|OwnerPartId=-1|Location.X=728|Location.Y=525|Color=8388608|FontID=1|IsHidden=T|Text=No|Name=Schmitt Trigger
|RECORD=41|OwnerIndex=586|IndexInSheet=30|OwnerPartId=-1|Location.X=728|Location.Y=525|Color=8388608|FontID=1|IsHidden=T|Text=Texas Instruments|Name=Manufacturer
|RECORD=41|OwnerIndex=586|IndexInSheet=31|OwnerPartId=-1|Location.X=728|Location.Y=525|Color=8388608|FontID=1|IsHidden=T|Text=1.65|Name=VCC(Min)(V)
|RECORD=41|OwnerIndex=586|IndexInSheet=32|OwnerPartId=-1|Location.X=728|Location.Y=525|Color=8388608|FontID=1|IsHidden=T|Text=No|Name=3-State Output
|RECORD=41|OwnerIndex=586|IndexInSheet=33|OwnerPartId=-1|Location.X=728|Location.Y=525|Color=8388608|FontID=1|IsHidden=T|Text=3|Name=Bits(#)
|RECORD=41|OwnerIndex=586|IndexInSheet=34|OwnerPartId=-1|Location.X=728|Location.Y=525|Color=8388608|FontID=1|IsHidden=T|Text=SCES365K|Name=DatasheetVersion
|RECORD=41|OwnerIndex=586|IndexInSheet=35|OwnerPartId=-1|Location.X=728|Location.Y=525|Color=8388608|FontID=1|IsHidden=T|Text=CMOS/TTL|Name=Input Type
|RECORD=41|OwnerIndex=586|IndexInSheet=36|OwnerPartId=-1|Location.X=728|Location.Y=525|Color=8388608|FontID=1|IsHidden=T|Text=Catalog|Name=Rating
|RECORD=41|OwnerIndex=586|IndexInSheet=37|OwnerPartId=-1|Location.X=728|Location.Y=525|Color=8388608|FontID=1|IsHidden=T|Text=32/-32|Name=Output Drive (IOL/IOH)(Max)(mA)
|RECORD=41|OwnerIndex=586|IndexInSheet=38|OwnerPartId=-1|Location.X=728|Location.Y=525|Color=8388608|FontID=1|IsHidden=T|Text=-40 to 125,-40 to 85|Name=Operating Temperature Range(C)
|RECORD=34|OwnerIndex=586|IndexInSheet=-1|OwnerPartId=-1|Location.X=749|Location.Y=506|Color=8388608|FontID=1|Text=U3|Name=Designator|ReadOnlyState=1
|RECORD=41|OwnerIndex=586|IndexInSheet=-1|OwnerPartId=-1|Location.X=749|Location.Y=464|Color=8388608|FontID=1|Text=SN74LVC3G07DCUR|Name=Comment
|RECORD=44|OwnerIndex=586
|RECORD=45|OwnerIndex=636|IndexInSheet=-1|Description=SOP, 8-Leads, Body 2.4x2.1mm, Pitch 0.5mm, IPC Medium Density|UseComponentLibrary=T|ModelName=DCU0008A_N|ModelType=PCBLIB|DatafileCount=1|ModelDatafileEntity0=DCU0008A_N|ModelDatafileKind0=PCBLib|IsCurrent=T|DatalinksLocked=T|DatabaseDatalinksLocked=T
|RECORD=46|OwnerIndex=637
|RECORD=48|OwnerIndex=637
|RECORD=41|OwnerIndex=639|IndexInSheet=-1|OwnerPartId=-1|Color=8388608|FontID=1|IsHidden=T|Text=2D|Name=Available Preview Images
|RECORD=45|OwnerIndex=636|IndexInSheet=-1|Description=SOP, 8-Leads, Body 2.4x2.1mm, Pitch 0.5mm, IPC Low Density|UseComponentLibrary=T|ModelName=DCU0008A_M|ModelType=PCBLIB|DatafileCount=1|ModelDatafileEntity0=DCU0008A_M|ModelDatafileKind0=PCBLib|DatalinksLocked=T|DatabaseDatalinksLocked=T
|RECORD=46|OwnerIndex=641
|RECORD=48|OwnerIndex=641
|RECORD=41|OwnerIndex=643|IndexInSheet=-1|OwnerPartId=-1|Color=8388608|FontID=1|IsHidden=T|Text=2D|Name=Available Preview Images
|RECORD=45|OwnerIndex=636|IndexInSheet=-1|Description=SOP, 8-Leads, Body 2.4x2.1mm, Pitch 0.5mm, IPC High Density|UseComponentLibrary=T|ModelName=DCU0008A_L|ModelType=PCBLIB|DatafileCount=1|ModelDatafileEntity0=DCU0008A_L|ModelDatafileKind0=PCBLib|DatalinksLocked=T|DatabaseDatalinksLocked=T
|RECORD=46|OwnerIndex=645
|RECORD=48|OwnerIndex=645
|RECORD=41|OwnerIndex=647|IndexInSheet=-1|OwnerPartId=-1|Color=8388608|FontID=1|IsHidden=T|Text=2D|Name=Available Preview Images
|RECORD=1|LibReference=TI-SN74XXX3G0X-XX-8|ComponentDescription=Triple Buffer/Driver With Open-Drain Output, DCU0008A, LARGE T&R|PartCount=5|DisplayModeCount=1|IndexInSheet=63|OwnerPartId=-1|Location.X=750|Location.Y=440|CurrentPartId=1|LibraryPath=*|SourceLibraryName=Altium Content Vault|TargetFileName=*|AreaColor=11599871|Color=128|PartIDLocked=T|DesignItemId=CMP-0859-00615-3|AllPinCount=8
|RECORD=2|OwnerIndex=649|OwnerPartId=3|FormalType=1|Electrical=3|PinConglomerate=48|PinLength=20|Location.X=780|Location.Y=420|Name=3Y|Designator=2|SwapIDPart=Ž&Ž2|PinPropagationDelay=0.000000E+000
|RECORD=2|OwnerIndex=649|OwnerPartId=3|FormalType=1|PinConglomerate=50|PinLength=20|Location.X=750|Location.Y=420|Name=3A|Designator=6|SwapIDPart=Ž&Ž2|PinPropagationDelay=0.000000E+000
|RECORD=13|OwnerIndex=649|IsNotAccesible=T|IndexInSheet=2|OwnerPartId=3|Location.X=750|Location.Y=435|Corner.X=780|Corner.Y=420|LineWidth=1|Color=16711680
|RECORD=13|OwnerIndex=649|IsNotAccesible=T|IndexInSheet=3|OwnerPartId=3|Location.X=750|Location.Y=405|Corner.X=780|Corner.Y=420|LineWidth=1|Color=16711680
|RECORD=13|OwnerIndex=649|IsNotAccesible=T|IndexInSheet=4|OwnerPartId=3|Location.X=750|Location.Y=405|Corner.X=750|Corner.Y=435|LineWidth=1|Color=16711680
|RECORD=2|OwnerIndex=649|OwnerPartId=2|FormalType=1|Electrical=3|PinConglomerate=48|PinLength=20|Location.X=780|Location.Y=420|Name=2Y|Designator=5|SwapIDPart=Ž&Ž2|PinPropagationDelay=0.000000E+000
|RECORD=2|OwnerIndex=649|OwnerPartId=2|FormalType=1|PinConglomerate=50|PinLength=20|Location.X=750|Location.Y=420|Name=2A|Designator=3|SwapIDPart=Ž&Ž2|PinPropagationDelay=0.000000E+000
|RECORD=13|OwnerIndex=649|IsNotAccesible=T|IndexInSheet=7|OwnerPartId=2|Location.X=750|Location.Y=435|Corner.X=780|Corner.Y=420|LineWidth=1|Color=16711680
|RECORD=13|OwnerIndex=649|IsNotAccesible=T|IndexInSheet=8|OwnerPartId=2|Location.X=750|Location.Y=405|Corner.X=780|Corner.Y=420|LineWidth=1|Color=16711680
|RECORD=13|OwnerIndex=649|IsNotAccesible=T|IndexInSheet=9|OwnerPartId=2|Location.X=750|Location.Y=405|Corner.X=750|Corner.Y=435|LineWidth=1|Color=16711680
|RECORD=14|OwnerIndex=649|IsNotAccesible=T|IndexInSheet=10|OwnerPartId=4|Location.X=750|Location.Y=420|Corner.X=810|Corner.Y=440|Color=128|AreaColor=11599871|IsSolid=T
|RECORD=2|OwnerIndex=649|OwnerPartId=4|FormalType=1|Electrical=7|PinConglomerate=56|PinLength=20|Location.X=810|Location.Y=430|Name=GND|Designator=4|PinPropagationDelay=0.000000E+000
|RECORD=2|OwnerIndex=649|OwnerPartId=4|FormalType=1|Electrical=7|PinConglomerate=58|PinLength=20|Location.X=750|Location.Y=430|Name=VCC|Designator=8|PinPropagationDelay=0.000000E+000
|RECORD=2|OwnerIndex=649|OwnerPartId=1|FormalType=1|Electrical=3|PinConglomerate=48|PinLength=20|Location.X=780|Location.Y=420|Name=1Y|Designator=7|SwapIDPart=Ž&Ž2|PinPropagationDelay=0.000000E+000
|RECORD=2|OwnerIndex=649|OwnerPartId=1|FormalType=1|PinConglomerate=50|PinLength=20|Location.X=750|Location.Y=420|Name=1A|Designator=1|SwapIDPart=Ž&Ž2|PinPropagationDelay=0.000000E+000
|RECORD=13|OwnerIndex=649|IsNotAccesible=T|IndexInSheet=15|OwnerPartId=1|Location.X=750|Location.Y=435|Corner.X=780|Corner.Y=420|LineWidth=1|Color=16711680
|RECORD=13|OwnerIndex=649|IsNotAccesible=T|IndexInSheet=16|OwnerPartId=1|Location.X=750|Location.Y=405|Corner.X=780|Corner.Y=420|LineWidth=1|Color=16711680
|RECORD=13|OwnerIndex=649|IsNotAccesible=T|IndexInSheet=17|OwnerPartId=1|Location.X=750|Location.Y=405|Corner.X=750|Corner.Y=435|LineWidth=1|Color=16711680
|RECORD=41|OwnerIndex=649|IndexInSheet=18|OwnerPartId=-1|Location.X=728|Location.Y=455|Color=8388608|FontID=1|IsHidden=T|Text=SN74LVC3G07|Name=Generic Part Number
|RECORD=41|OwnerIndex=649|IndexInSheet=19|OwnerPartId=-1|Location.X=728|Location.Y=455|Color=8388608|FontID=1|IsHidden=T|Text=5.5|Name=VCC(Max)(V)
|RECORD=41|OwnerIndex=649|IndexInSheet=20|OwnerPartId=-1|Location.X=728|Location.Y=455|Color=8388608|FontID=1|IsHidden=T|Text=Non-Inverting Buffer/Driver|Name=Sub-Family
|RECORD=41|OwnerIndex=649|IndexInSheet=21|OwnerPartId=-1|Location.X=728|Location.Y=455|Color=8388608|FontID=1|IsHidden=T|Text=True|Name=Logic
|RECORD=41|OwnerIndex=649|IndexInSheet=22|OwnerPartId=-1|Location.X=728|Location.Y=455|Color=8388608|FontID=1|IsHidden=T|Text=DCU0008A|Name=PackageReference
|RECORD=41|OwnerIndex=649|IndexInSheet=23|OwnerPartId=-1|Location.X=728|Location.Y=455|Color=8388608|FontID=1|IsHidden=T|Text=8.3,4.8,4.2,3.4|Name=tpd @ Nom Voltage(Max)(ns)
|RECORD=41|OwnerIndex=649|IndexInSheet=24|OwnerPartId=-1|Location.X=728|Location.Y=455|Color=8388608|FontID=1|IsHidden=T|Text=CMOS|Name=Output Type
|RECORD=41|OwnerIndex=649|IndexInSheet=25|OwnerPartId=-1|Location.X=728|Location.Y=455|Color=8388608|FontID=1|IsHidden=T|Text=150|Name=F @ Nom Voltage(Max)(Mhz)
|RECORD=41|OwnerIndex=649|IndexInSheet=26|OwnerPartId=-1|Location.X=728|Location.Y=455|Color=8388608|FontID=1|IsHidden=T|Text=LVC|Name=Technology Family
|RECORD=41|OwnerIndex=649|IndexInSheet=27|OwnerPartId=-1|Location.X=728|Location.Y=455|Color=8388608|FontID=1|IsHidden=T|Text=0.01|Name=ICC @ Nom Voltage(Max)(mA)
|RECORD=41|OwnerIndex=649|IndexInSheet=28|OwnerPartId=-1|Location.X=728|Location.Y=455|Color=8388608|FontID=1|IsHidden=T|Text=1.8,2.5,3.3,5|Name=Voltage(Nom)(V)
|RECORD=41|OwnerIndex=649|IndexInSheet=29|OwnerPartId=-1|Location.X=728|Location.Y=455|Color=8388608|FontID=1|IsHidden=T|Text=No|Name=Schmitt Trigger
|RECORD=41|OwnerIndex=649|IndexInSheet=30|OwnerPartId=-1|Location.X=728|Location.Y=455|Color=8388608|FontID=1|IsHidden=T|Text=Texas Instruments|Name=Manufacturer
|RECORD=41|OwnerIndex=649|IndexInSheet=31|OwnerPartId=-1|Location.X=728|Location.Y=455|Color=8388608|FontID=1|IsHidden=T|Text=1.65|Name=VCC(Min)(V)
|RECORD=41|OwnerIndex=649|IndexInSheet=32|OwnerPartId=-1|Location.X=728|Location.Y=455|Color=8388608|FontID=1|IsHidden=T|Text=No|Name=3-State Output
|RECORD=41|OwnerIndex=649|IndexInSheet=33|OwnerPartId=-1|Location.X=728|Location.Y=455|Color=8388608|FontID=1|IsHidden=T|Text=3|Name=Bits(#)
|RECORD=41|OwnerIndex=649|IndexInSheet=34|OwnerPartId=-1|Location.X=728|Location.Y=455|Color=8388608|FontID=1|IsHidden=T|Text=SCES365K|Name=DatasheetVersion
|RECORD=41|OwnerIndex=649|IndexInSheet=35|OwnerPartId=-1|Location.X=728|Location.Y=455|Color=8388608|FontID=1|IsHidden=T|Text=CMOS/TTL|Name=Input Type
|RECORD=41|OwnerIndex=649|IndexInSheet=36|OwnerPartId=-1|Location.X=728|Location.Y=455|Color=8388608|FontID=1|IsHidden=T|Text=Catalog|Name=Rating
|RECORD=41|OwnerIndex=649|IndexInSheet=37|OwnerPartId=-1|Location.X=728|Location.Y=455|Color=8388608|FontID=1|IsHidden=T|Text=32/-32|Name=Output Drive (IOL/IOH)(Max)(mA)
|RECORD=41|OwnerIndex=649|IndexInSheet=38|OwnerPartId=-1|Location.X=728|Location.Y=455|Color=8388608|FontID=1|IsHidden=T|Text=-40 to 125,-40 to 85|Name=Operating Temperature Range(C)
|RECORD=34|OwnerIndex=649|IndexInSheet=-1|OwnerPartId=-1|Location.X=749|Location.Y=436|Color=8388608|FontID=1|Text=U3|Name=Designator|ReadOnlyState=1
|RECORD=41|OwnerIndex=649|IndexInSheet=-1|OwnerPartId=-1|Location.X=749|Location.Y=394|Color=8388608|FontID=1|Text=SN74LVC3G07DCUR|Name=Comment
|RECORD=44|OwnerIndex=649
|RECORD=45|OwnerIndex=699|IndexInSheet=-1|Description=SOP, 8-Leads, Body 2.4x2.1mm, Pitch 0.5mm, IPC Medium Density|UseComponentLibrary=T|ModelName=DCU0008A_N|ModelType=PCBLIB|DatafileCount=1|ModelDatafileEntity0=DCU0008A_N|ModelDatafileKind0=PCBLib|IsCurrent=T|DatalinksLocked=T|DatabaseDatalinksLocked=T
|RECORD=46|OwnerIndex=700
|RECORD=48|OwnerIndex=700
|RECORD=41|OwnerIndex=702|IndexInSheet=-1|OwnerPartId=-1|Color=8388608|FontID=1|IsHidden=T|Text=2D|Name=Available Preview Images
|RECORD=45|OwnerIndex=699|IndexInSheet=-1|Description=SOP, 8-Leads, Body 2.4x2.1mm, Pitch 0.5mm, IPC Low Density|UseComponentLibrary=T|ModelName=DCU0008A_M|ModelType=PCBLIB|DatafileCount=1|ModelDatafileEntity0=DCU0008A_M|ModelDatafileKind0=PCBLib|DatalinksLocked=T|DatabaseDatalinksLocked=T
|RECORD=46|OwnerIndex=704
|RECORD=48|OwnerIndex=704
|RECORD=41|OwnerIndex=706|IndexInSheet=-1|OwnerPartId=-1|Color=8388608|FontID=1|IsHidden=T|Text=2D|Name=Available Preview Images
|RECORD=45|OwnerIndex=699|IndexInSheet=-1|Description=SOP, 8-Leads, Body 2.4x2.1mm, Pitch 0.5mm, IPC High Density|UseComponentLibrary=T|ModelName=DCU0008A_L|ModelType=PCBLIB|DatafileCount=1|ModelDatafileEntity0=DCU0008A_L|ModelDatafileKind0=PCBLib|DatalinksLocked=T|DatabaseDatalinksLocked=T
|RECORD=46|OwnerIndex=708
|RECORD=48|OwnerIndex=708
|RECORD=41|OwnerIndex=710|IndexInSheet=-1|OwnerPartId=-1|Color=8388608|FontID=1|IsHidden=T|Text=2D|Name=Available Preview Images
|RECORD=1|LibReference=TI-SN74XXX3G0X-XX-8|ComponentDescription=Triple Buffer/Driver With Open-Drain Output, DCU0008A, LARGE T&R|PartCount=5|DisplayModeCount=1|IndexInSheet=64|OwnerPartId=-1|Location.X=750|Location.Y=370|CurrentPartId=2|LibraryPath=*|SourceLibraryName=Altium Content Vault|TargetFileName=*|AreaColor=11599871|Color=128|PartIDLocked=F|DesignItemId=CMP-0859-00615-3|AllPinCount=8
|RECORD=2|OwnerIndex=712|OwnerPartId=3|FormalType=1|Electrical=3|PinConglomerate=48|PinLength=20|Location.X=780|Location.Y=350|Name=3Y|Designator=2|SwapIDPart=Ž&Ž2|PinPropagationDelay=0.000000E+000
|RECORD=2|OwnerIndex=712|OwnerPartId=3|FormalType=1|PinConglomerate=50|PinLength=20|Location.X=750|Location.Y=350|Name=3A|Designator=6|SwapIDPart=Ž&Ž2|PinPropagationDelay=0.000000E+000
|RECORD=13|OwnerIndex=712|IsNotAccesible=T|IndexInSheet=2|OwnerPartId=3|Location.X=750|Location.Y=365|Corner.X=780|Corner.Y=350|LineWidth=1|Color=16711680
|RECORD=13|OwnerIndex=712|IsNotAccesible=T|IndexInSheet=3|OwnerPartId=3|Location.X=750|Location.Y=335|Corner.X=780|Corner.Y=350|LineWidth=1|Color=16711680
|RECORD=13|OwnerIndex=712|IsNotAccesible=T|IndexInSheet=4|OwnerPartId=3|Location.X=750|Location.Y=335|Corner.X=750|Corner.Y=365|LineWidth=1|Color=16711680
|RECORD=2|OwnerIndex=712|OwnerPartId=2|FormalType=1|Electrical=3|PinConglomerate=48|PinLength=20|Location.X=780|Location.Y=350|Name=2Y|Designator=5|SwapIDPart=Ž&Ž2|PinPropagationDelay=0.000000E+000
|RECORD=2|OwnerIndex=712|OwnerPartId=2|FormalType=1|PinConglomerate=50|PinLength=20|Location.X=750|Location.Y=350|Name=2A|Designator=3|SwapIDPart=Ž&Ž2|PinPropagationDelay=0.000000E+000
|RECORD=13|OwnerIndex=712|IsNotAccesible=T|IndexInSheet=7|OwnerPartId=2|Location.X=750|Location.Y=365|Corner.X=780|Corner.Y=350|LineWidth=1|Color=16711680
|RECORD=13|OwnerIndex=712|IsNotAccesible=T|IndexInSheet=8|OwnerPartId=2|Location.X=750|Location.Y=335|Corner.X=780|Corner.Y=350|LineWidth=1|Color=16711680
|RECORD=13|OwnerIndex=712|IsNotAccesible=T|IndexInSheet=9|OwnerPartId=2|Location.X=750|Location.Y=335|Corner.X=750|Corner.Y=365|LineWidth=1|Color=16711680
|RECORD=14|OwnerIndex=712|IsNotAccesible=T|IndexInSheet=10|OwnerPartId=4|Location.X=750|Location.Y=350|Corner.X=810|Corner.Y=370|Color=128|AreaColor=11599871|IsSolid=T
|RECORD=2|OwnerIndex=712|OwnerPartId=4|FormalType=1|Electrical=7|PinConglomerate=56|PinLength=20|Location.X=810|Location.Y=360|Name=GND|Designator=4|PinPropagationDelay=0.000000E+000
|RECORD=2|OwnerIndex=712|OwnerPartId=4|FormalType=1|Electrical=7|PinConglomerate=58|PinLength=20|Location.X=750|Location.Y=360|Name=VCC|Designator=8|PinPropagationDelay=0.000000E+000
|RECORD=2|OwnerIndex=712|OwnerPartId=1|FormalType=1|Electrical=3|PinConglomerate=48|PinLength=20|Location.X=780|Location.Y=350|Name=1Y|Designator=7|SwapIDPart=Ž&Ž2|PinPropagationDelay=0.000000E+000
|RECORD=2|OwnerIndex=712|OwnerPartId=1|FormalType=1|PinConglomerate=50|PinLength=20|Location.X=750|Location.Y=350|Name=1A|Designator=1|SwapIDPart=Ž&Ž2|PinPropagationDelay=0.000000E+000
|RECORD=13|OwnerIndex=712|IsNotAccesible=T|IndexInSheet=15|OwnerPartId=1|Location.X=750|Location.Y=365|Corner.X=780|Corner.Y=350|LineWidth=1|Color=16711680
|RECORD=13|OwnerIndex=712|IsNotAccesible=T|IndexInSheet=16|OwnerPartId=1|Location.X=750|Location.Y=335|Corner.X=780|Corner.Y=350|LineWidth=1|Color=16711680
|RECORD=13|OwnerIndex=712|IsNotAccesible=T|IndexInSheet=17|OwnerPartId=1|Location.X=750|Location.Y=335|Corner.X=750|Corner.Y=365|LineWidth=1|Color=16711680
|RECORD=41|OwnerIndex=712|IndexInSheet=18|OwnerPartId=-1|Location.X=728|Location.Y=385|Color=8388608|FontID=1|IsHidden=T|Text=SN74LVC3G07|Name=Generic Part Number
|RECORD=41|OwnerIndex=712|IndexInSheet=19|OwnerPartId=-1|Location.X=728|Location.Y=385|Color=8388608|FontID=1|IsHidden=T|Text=5.5|Name=VCC(Max)(V)
|RECORD=41|OwnerIndex=712|IndexInSheet=20|OwnerPartId=-1|Location.X=728|Location.Y=385|Color=8388608|FontID=1|IsHidden=T|Text=Non-Inverting Buffer/Driver|Name=Sub-Family
|RECORD=41|OwnerIndex=712|IndexInSheet=21|OwnerPartId=-1|Location.X=728|Location.Y=385|Color=8388608|FontID=1|IsHidden=T|Text=True|Name=Logic
|RECORD=41|OwnerIndex=712|IndexInSheet=22|OwnerPartId=-1|Location.X=728|Location.Y=385|Color=8388608|FontID=1|IsHidden=T|Text=DCU0008A|Name=PackageReference
|RECORD=41|OwnerIndex=712|IndexInSheet=23|OwnerPartId=-1|Location.X=728|Location.Y=385|Color=8388608|FontID=1|IsHidden=T|Text=8.3,4.8,4.2,3.4|Name=tpd @ Nom Voltage(Max)(ns)
|RECORD=41|OwnerIndex=712|IndexInSheet=24|OwnerPartId=-1|Location.X=728|Location.Y=385|Color=8388608|FontID=1|IsHidden=T|Text=CMOS|Name=Output Type
|RECORD=41|OwnerIndex=712|IndexInSheet=25|OwnerPartId=-1|Location.X=728|Location.Y=385|Color=8388608|FontID=1|IsHidden=T|Text=150|Name=F @ Nom Voltage(Max)(Mhz)
|RECORD=41|OwnerIndex=712|IndexInSheet=26|OwnerPartId=-1|Location.X=728|Location.Y=385|Color=8388608|FontID=1|IsHidden=T|Text=LVC|Name=Technology Family
|RECORD=41|OwnerIndex=712|IndexInSheet=27|OwnerPartId=-1|Location.X=728|Location.Y=385|Color=8388608|FontID=1|IsHidden=T|Text=0.01|Name=ICC @ Nom Voltage(Max)(mA)
|RECORD=41|OwnerIndex=712|IndexInSheet=28|OwnerPartId=-1|Location.X=728|Location.Y=385|Color=8388608|FontID=1|IsHidden=T|Text=1.8,2.5,3.3,5|Name=Voltage(Nom)(V)
|RECORD=41|OwnerIndex=712|IndexInSheet=29|OwnerPartId=-1|Location.X=728|Location.Y=385|Color=8388608|FontID=1|IsHidden=T|Text=No|Name=Schmitt Trigger
|RECORD=41|OwnerIndex=712|IndexInSheet=30|OwnerPartId=-1|Location.X=728|Location.Y=385|Color=8388608|FontID=1|IsHidden=T|Text=Texas Instruments|Name=Manufacturer
|RECORD=41|OwnerIndex=712|IndexInSheet=31|OwnerPartId=-1|Location.X=728|Location.Y=385|Color=8388608|FontID=1|IsHidden=T|Text=1.65|Name=VCC(Min)(V)
|RECORD=41|OwnerIndex=712|IndexInSheet=32|OwnerPartId=-1|Location.X=728|Location.Y=385|Color=8388608|FontID=1|IsHidden=T|Text=No|Name=3-State Output
|RECORD=41|OwnerIndex=712|IndexInSheet=33|OwnerPartId=-1|Location.X=728|Location.Y=385|Color=8388608|FontID=1|IsHidden=T|Text=3|Name=Bits(#)
|RECORD=41|OwnerIndex=712|IndexInSheet=34|OwnerPartId=-1|Location.X=728|Location.Y=385|Color=8388608|FontID=1|IsHidden=T|Text=SCES365K|Name=DatasheetVersion
|RECORD=41|OwnerIndex=712|IndexInSheet=35|OwnerPartId=-1|Location.X=728|Location.Y=385|Color=8388608|FontID=1|IsHidden=T|Text=CMOS/TTL|Name=Input Type
|RECORD=41|OwnerIndex=712|IndexInSheet=36|OwnerPartId=-1|Location.X=728|Location.Y=385|Color=8388608|FontID=1|IsHidden=T|Text=Catalog|Name=Rating
|RECORD=41|OwnerIndex=712|IndexInSheet=37|OwnerPartId=-1|Location.X=728|Location.Y=385|Color=8388608|FontID=1|IsHidden=T|Text=32/-32|Name=Output Drive (IOL/IOH)(Max)(mA)
|RECORD=41|OwnerIndex=712|IndexInSheet=38|OwnerPartId=-1|Location.X=728|Location.Y=385|Color=8388608|FontID=1|IsHidden=T|Text=-40 to 125,-40 to 85|Name=Operating Temperature Range(C)
|RECORD=34|OwnerIndex=712|IndexInSheet=-1|OwnerPartId=-1|Location.X=749|Location.Y=366|Color=8388608|FontID=1|Text=U3|Name=Designator|ReadOnlyState=1
|RECORD=41|OwnerIndex=712|IndexInSheet=-1|OwnerPartId=-1|Location.X=749|Location.Y=324|Color=8388608|FontID=1|Text=SN74LVC3G07DCUR|Name=Comment
|RECORD=44|OwnerIndex=712
|RECORD=45|OwnerIndex=762|IndexInSheet=-1|Description=SOP, 8-Leads, Body 2.4x2.1mm, Pitch 0.5mm, IPC Medium Density|UseComponentLibrary=T|ModelName=DCU0008A_N|ModelType=PCBLIB|DatafileCount=1|ModelDatafileEntity0=DCU0008A_N|ModelDatafileKind0=PCBLib|IsCurrent=T|DatalinksLocked=T|DatabaseDatalinksLocked=T
|RECORD=46|OwnerIndex=763
|RECORD=48|OwnerIndex=763
|RECORD=41|OwnerIndex=765|IndexInSheet=-1|OwnerPartId=-1|Color=8388608|FontID=1|IsHidden=T|Text=2D|Name=Available Preview Images
|RECORD=45|OwnerIndex=762|IndexInSheet=-1|Description=SOP, 8-Leads, Body 2.4x2.1mm, Pitch 0.5mm, IPC Low Density|UseComponentLibrary=T|ModelName=DCU0008A_M|ModelType=PCBLIB|DatafileCount=1|ModelDatafileEntity0=DCU0008A_M|ModelDatafileKind0=PCBLib|DatalinksLocked=T|DatabaseDatalinksLocked=T
|RECORD=46|OwnerIndex=767
|RECORD=48|OwnerIndex=767
|RECORD=41|OwnerIndex=769|IndexInSheet=-1|OwnerPartId=-1|Color=8388608|FontID=1|IsHidden=T|Text=2D|Name=Available Preview Images
|RECORD=45|OwnerIndex=762|IndexInSheet=-1|Description=SOP, 8-Leads, Body 2.4x2.1mm, Pitch 0.5mm, IPC High Density|UseComponentLibrary=T|ModelName=DCU0008A_L|ModelType=PCBLIB|DatafileCount=1|ModelDatafileEntity0=DCU0008A_L|ModelDatafileKind0=PCBLib|DatalinksLocked=T|DatabaseDatalinksLocked=T
|RECORD=46|OwnerIndex=771
|RECORD=48|OwnerIndex=771
|RECORD=41|OwnerIndex=773|IndexInSheet=-1|OwnerPartId=-1|Color=8388608|FontID=1|IsHidden=T|Text=2D|Name=Available Preview Images
|RECORD=1|LibReference=1029c3af85768c4190bb7ad29bc67b5|ComponentDescription=1kO ±1% 0.063W 0402 Thick Film Chip Resistor AEC-Q200 compliant|PartCount=2|DisplayModeCount=1|IndexInSheet=65|OwnerPartId=-1|Location.X=150|Location.Y=40|Orientation=1|CurrentPartId=1|LibraryPath=*|SourceLibraryName=Altium Content Vault|TargetFileName=*|AreaColor=11599871|Color=128|PartIDLocked=T|DesignItemId=CMP-26527-000026-1|AllPinCount=2
|RECORD=2|OwnerIndex=775|OwnerPartId=1|Electrical=4|PinConglomerate=35|PinLength=20|Location.X=150|Location.Y=60|Name=1|Designator=1|PinPropagationDelay=0.000000E+000
|RECORD=2|OwnerIndex=775|OwnerPartId=1|Electrical=4|PinConglomerate=33|PinLength=20|Location.X=150|Location.Y=90|Name=2|Designator=2|PinPropagationDelay=0.000000E+000
|RECORD=13|OwnerIndex=775|IsNotAccesible=T|IndexInSheet=2|OwnerPartId=1|Location.X=150|Location.Y=60|Corner.X=145|Corner.Y=63|LineWidth=1|Color=16711680
|RECORD=13|OwnerIndex=775|IsNotAccesible=T|IndexInSheet=3|OwnerPartId=1|Location.X=145|Location.Y=63|Corner.X=155|Corner.Y=68|LineWidth=1|Color=16711680
|RECORD=13|OwnerIndex=775|IsNotAccesible=T|IndexInSheet=4|OwnerPartId=1|Location.X=155|Location.Y=68|Corner.X=145|Corner.Y=73|LineWidth=1|Color=16711680
|RECORD=13|OwnerIndex=775|IsNotAccesible=T|IndexInSheet=5|OwnerPartId=1|Location.X=145|Location.Y=73|Corner.X=155|Corner.Y=78|LineWidth=1|Color=16711680
|RECORD=13|OwnerIndex=775|IsNotAccesible=T|IndexInSheet=6|OwnerPartId=1|Location.X=155|Location.Y=78|Corner.X=145|Corner.Y=83|LineWidth=1|Color=16711680
|RECORD=13|OwnerIndex=775|IsNotAccesible=T|IndexInSheet=7|OwnerPartId=1|Location.X=145|Location.Y=83|Corner.X=155|Corner.Y=88|LineWidth=1|Color=16711680
|RECORD=13|OwnerIndex=775|IsNotAccesible=T|IndexInSheet=8|OwnerPartId=1|Location.X=155|Location.Y=88|Corner.X=150|Corner.Y=90|LineWidth=1|Color=16711680
|RECORD=13|OwnerIndex=775|IsNotAccesible=T|IndexInSheet=9|OwnerPartId=1|Location.X=150|Location.Y=60|Corner.X=150|Corner.Y=57|LineWidth=1|Color=16711680
|RECORD=13|OwnerIndex=775|IsNotAccesible=T|IndexInSheet=10|OwnerPartId=1|Location.X=150|Location.Y=90|Corner.X=150|Corner.Y=93|LineWidth=1|Color=16711680
|RECORD=41|OwnerIndex=775|IndexInSheet=11|OwnerPartId=-1|Location.X=144|Location.Y=112|Color=8388608|FontID=1|IsHidden=T|Text=1mm|Name=Length
|RECORD=41|OwnerIndex=775|IndexInSheet=12|OwnerPartId=-1|Location.X=144|Location.Y=112|Color=8388608|FontID=1|IsHidden=T|Text=Yes|Name=RoHS Compliant
|RECORD=41|OwnerIndex=775|IndexInSheet=13|OwnerPartId=-1|Location.X=144|Location.Y=112|Color=8388608|FontID=1|IsHidden=T|Text=Rectangular|Name=Construction
|RECORD=41|OwnerIndex=775|IndexInSheet=14|OwnerPartId=-1|Location.X=144|Location.Y=112|Color=8388608|FontID=1|IsHidden=T|Text=0.016inch|Name=Height
|RECORD=41|OwnerIndex=775|IndexInSheet=15|OwnerPartId=-1|Location.X=144|Location.Y=112|Color=8388608|FontID=1|IsHidden=T|Text=0402|Name=Size Code
|RECORD=41|OwnerIndex=775|IndexInSheet=16|OwnerPartId=-1|Location.X=144|Location.Y=112|Color=8388608|FontID=1|IsHidden=T|Text=Lead Free|Name=Lead Free
|RECORD=41|OwnerIndex=775|IndexInSheet=17|OwnerPartId=-1|Location.X=144|Location.Y=112|Color=8388608|FontID=1|IsHidden=T|Text=No|Name=Radiation Hardening
|RECORD=41|OwnerIndex=775|IndexInSheet=18|OwnerPartId=-1|Location.X=144|Location.Y=112|Color=8388608|FontID=1|IsHidden=T|Text=1%|Name=Tolerance
|RECORD=41|OwnerIndex=775|IndexInSheet=19|OwnerPartId=-1|Location.X=144|Location.Y=112|Color=8388608|FontID=1|IsHidden=T|Text=0.02inch|Name=Width
|RECORD=41|OwnerIndex=775|IndexInSheet=20|OwnerPartId=-1|Location.X=144|Location.Y=112|Color=8388608|FontID=1|IsHidden=T|Text=1kR|Name=Resistance
|RECORD=41|OwnerIndex=775|IndexInSheet=21|OwnerPartId=-1|Location.X=144|Location.Y=112|Color=8388608|FontID=1|IsHidden=T|Text=Not|Name=Military Standard
|RECORD=41|OwnerIndex=775|IndexInSheet=22|OwnerPartId=-1|Location.X=144|Location.Y=112|Color=8388608|FontID=1|IsHidden=T|Text=Thick Film|Name=Resistor Type
|RECORD=41|OwnerIndex=775|IndexInSheet=23|OwnerPartId=-1|Location.X=144|Location.Y=112|Color=8388608|FontID=1|IsHidden=T|Text=100ppm/°C|Name=Temperature Coefficient
|RECORD=41|OwnerIndex=775|IndexInSheet=24|OwnerPartId=-1|Location.X=144|Location.Y=112|Color=8388608|FontID=1|IsHidden=T|Text=2|Name=Number of Terminations
|RECORD=41|OwnerIndex=775|IndexInSheet=25|OwnerPartId=-1|Location.X=144|Location.Y=112|Color=8388608|FontID=1|IsHidden=T|Text=-55°C|Name=Min Operating Temperature
|RECORD=41|OwnerIndex=775|IndexInSheet=26|OwnerPartId=-1|Location.X=144|Location.Y=112|Color=8388608|FontID=1|IsHidden=T|Text=155°C|Name=Max Operating Temperature
|RECORD=41|OwnerIndex=775|IndexInSheet=27|OwnerPartId=-1|Location.X=144|Location.Y=112|Color=8388608|FontID=1|IsHidden=T|Text=63mW|Name=Power Rating
|RECORD=41|OwnerIndex=775|IndexInSheet=28|OwnerPartId=-1|Location.X=144|Location.Y=112|Color=8388608|FontID=1|IsHidden=T|Text=0.5mm|Name=Depth
|RECORD=41|OwnerIndex=775|IndexInSheet=29|OwnerPartId=-1|Location.X=144|Location.Y=112|Color=8388608|FontID=1|IsHidden=T|Text=Automotive AEC-Q200|Name=Features
|RECORD=41|OwnerIndex=775|IndexInSheet=30|OwnerPartId=-1|Location.X=144|Location.Y=112|Color=8388608|FontID=1|IsHidden=T|Text=Tape and Reel|Name=Packaging
|RECORD=41|OwnerIndex=775|IndexInSheet=31|OwnerPartId=-1|Location.X=144|Location.Y=112|Color=8388608|FontID=1|IsHidden=T|Text=1005|Name=Case Code (Metric)
|RECORD=41|OwnerIndex=775|IndexInSheet=32|OwnerPartId=-1|Location.X=144|Location.Y=112|Color=8388608|FontID=1|IsHidden=T|Text=Surface Mount|Name=Mount
|RECORD=41|OwnerIndex=775|IndexInSheet=33|OwnerPartId=-1|Location.X=144|Location.Y=112|Color=8388608|FontID=1|IsHidden=T|Text=Tin|Name=Contact Plating
|RECORD=41|OwnerIndex=775|IndexInSheet=34|OwnerPartId=-1|Location.X=144|Location.Y=112|Color=8388608|FontID=1|IsHidden=T|Text=63mW|Name=Max Power Dissipation
|RECORD=41|OwnerIndex=775|IndexInSheet=35|OwnerPartId=-1|Location.X=144|Location.Y=112|Color=8388608|FontID=1|IsHidden=T|Text=0402|Name=Case/Package
|RECORD=41|OwnerIndex=775|IndexInSheet=36|OwnerPartId=-1|Location.X=144|Location.Y=112|Color=8388608|FontID=1|IsHidden=T|Text=0402|Name=Case Code (Imperial)
|RECORD=41|OwnerIndex=775|IndexInSheet=37|OwnerPartId=-1|Location.X=144|Location.Y=112|Color=8388608|FontID=1|IsHidden=T|Text=RMCF|Name=Series
|RECORD=34|OwnerIndex=775|IndexInSheet=-1|OwnerPartId=-1|Location.X=156|Location.Y=84|Color=8388608|FontID=1|Text=R17|Name=Designator|ReadOnlyState=1
|RECORD=41|OwnerIndex=775|IndexInSheet=-1|OwnerPartId=1|Location.X=156|Location.Y=74|Color=8388608|FontID=1|Text=1k|Name=Comment
|RECORD=44|OwnerIndex=775
|RECORD=45|OwnerIndex=818|IndexInSheet=-1|UseComponentLibrary=T|ModelName=FP-RMCF0402-MFG|ModelType=PCBLIB|DatafileCount=1|ModelDatafileEntity0=FP-RMCF0402-MFG|ModelDatafileKind0=PCBLib|IsCurrent=T|DatalinksLocked=T|DatabaseDatalinksLocked=T
|RECORD=46|OwnerIndex=819
|RECORD=48|OwnerIndex=819
|RECORD=45|OwnerIndex=818|IndexInSheet=-1|UseComponentLibrary=T|ModelName=FP-RMCF0402-IPC_C|ModelType=PCBLIB|DatafileCount=1|ModelDatafileEntity0=FP-RMCF0402-IPC_C|ModelDatafileKind0=PCBLib|DatalinksLocked=T|DatabaseDatalinksLocked=T
|RECORD=46|OwnerIndex=822
|RECORD=48|OwnerIndex=822
|RECORD=45|OwnerIndex=818|IndexInSheet=-1|UseComponentLibrary=T|ModelName=FP-RMCF0402-IPC_B|ModelType=PCBLIB|DatafileCount=1|ModelDatafileEntity0=FP-RMCF0402-IPC_B|ModelDatafileKind0=PCBLib|DatalinksLocked=T|DatabaseDatalinksLocked=T
|RECORD=46|OwnerIndex=825
|RECORD=48|OwnerIndex=825
|RECORD=45|OwnerIndex=818|IndexInSheet=-1|UseComponentLibrary=T|ModelName=FP-RMCF0402-IPC_A|ModelType=PCBLIB|DatafileCount=1|ModelDatafileEntity0=FP-RMCF0402-IPC_A|ModelDatafileKind0=PCBLib|DatalinksLocked=T|DatabaseDatalinksLocked=T
|RECORD=46|OwnerIndex=828
|RECORD=48|OwnerIndex=828
|RECORD=1|LibReference=1029c3af85768c4190bb7ad29bc67b5|ComponentDescription=1kO ±1% 0.063W 0402 Thick Film Chip Resistor AEC-Q200 compliant|PartCount=2|DisplayModeCount=1|IndexInSheet=66|OwnerPartId=-1|Location.X=270|Location.Y=40|Orientation=1|CurrentPartId=1|LibraryPath=*|SourceLibraryName=Altium Content Vault|TargetFileName=*|AreaColor=11599871|Color=128|PartIDLocked=T|DesignItemId=CMP-26527-000026-1|AllPinCount=2
|RECORD=2|OwnerIndex=831|OwnerPartId=1|Electrical=4|PinConglomerate=35|PinLength=20|Location.X=270|Location.Y=60|Name=1|Designator=1|PinPropagationDelay=0.000000E+000
|RECORD=2|OwnerIndex=831|OwnerPartId=1|Electrical=4|PinConglomerate=33|PinLength=20|Location.X=270|Location.Y=90|Name=2|Designator=2|PinPropagationDelay=0.000000E+000
|RECORD=13|OwnerIndex=831|IsNotAccesible=T|IndexInSheet=2|OwnerPartId=1|Location.X=270|Location.Y=60|Corner.X=265|Corner.Y=63|LineWidth=1|Color=16711680
|RECORD=13|OwnerIndex=831|IsNotAccesible=T|IndexInSheet=3|OwnerPartId=1|Location.X=265|Location.Y=63|Corner.X=275|Corner.Y=68|LineWidth=1|Color=16711680
|RECORD=13|OwnerIndex=831|IsNotAccesible=T|IndexInSheet=4|OwnerPartId=1|Location.X=275|Location.Y=68|Corner.X=265|Corner.Y=73|LineWidth=1|Color=16711680
|RECORD=13|OwnerIndex=831|IsNotAccesible=T|IndexInSheet=5|OwnerPartId=1|Location.X=265|Location.Y=73|Corner.X=275|Corner.Y=78|LineWidth=1|Color=16711680
|RECORD=13|OwnerIndex=831|IsNotAccesible=T|IndexInSheet=6|OwnerPartId=1|Location.X=275|Location.Y=78|Corner.X=265|Corner.Y=83|LineWidth=1|Color=16711680
|RECORD=13|OwnerIndex=831|IsNotAccesible=T|IndexInSheet=7|OwnerPartId=1|Location.X=265|Location.Y=83|Corner.X=275|Corner.Y=88|LineWidth=1|Color=16711680
|RECORD=13|OwnerIndex=831|IsNotAccesible=T|IndexInSheet=8|OwnerPartId=1|Location.X=275|Location.Y=88|Corner.X=270|Corner.Y=90|LineWidth=1|Color=16711680
|RECORD=13|OwnerIndex=831|IsNotAccesible=T|IndexInSheet=9|OwnerPartId=1|Location.X=270|Location.Y=60|Corner.X=270|Corner.Y=57|LineWidth=1|Color=16711680
|RECORD=13|OwnerIndex=831|IsNotAccesible=T|IndexInSheet=10|OwnerPartId=1|Location.X=270|Location.Y=90|Corner.X=270|Corner.Y=93|LineWidth=1|Color=16711680
|RECORD=41|OwnerIndex=831|IndexInSheet=11|OwnerPartId=-1|Location.X=264|Location.Y=112|Color=8388608|FontID=1|IsHidden=T|Text=1mm|Name=Length
|RECORD=41|OwnerIndex=831|IndexInSheet=12|OwnerPartId=-1|Location.X=264|Location.Y=112|Color=8388608|FontID=1|IsHidden=T|Text=Yes|Name=RoHS Compliant
|RECORD=41|OwnerIndex=831|IndexInSheet=13|OwnerPartId=-1|Location.X=264|Location.Y=112|Color=8388608|FontID=1|IsHidden=T|Text=Rectangular|Name=Construction
|RECORD=41|OwnerIndex=831|IndexInSheet=14|OwnerPartId=-1|Location.X=264|Location.Y=112|Color=8388608|FontID=1|IsHidden=T|Text=0.016inch|Name=Height
|RECORD=41|OwnerIndex=831|IndexInSheet=15|OwnerPartId=-1|Location.X=264|Location.Y=112|Color=8388608|FontID=1|IsHidden=T|Text=0402|Name=Size Code
|RECORD=41|OwnerIndex=831|IndexInSheet=16|OwnerPartId=-1|Location.X=264|Location.Y=112|Color=8388608|FontID=1|IsHidden=T|Text=Lead Free|Name=Lead Free
|RECORD=41|OwnerIndex=831|IndexInSheet=17|OwnerPartId=-1|Location.X=264|Location.Y=112|Color=8388608|FontID=1|IsHidden=T|Text=No|Name=Radiation Hardening
|RECORD=41|OwnerIndex=831|IndexInSheet=18|OwnerPartId=-1|Location.X=264|Location.Y=112|Color=8388608|FontID=1|IsHidden=T|Text=1%|Name=Tolerance
|RECORD=41|OwnerIndex=831|IndexInSheet=19|OwnerPartId=-1|Location.X=264|Location.Y=112|Color=8388608|FontID=1|IsHidden=T|Text=0.02inch|Name=Width
|RECORD=41|OwnerIndex=831|IndexInSheet=20|OwnerPartId=-1|Location.X=264|Location.Y=112|Color=8388608|FontID=1|IsHidden=T|Text=1kR|Name=Resistance
|RECORD=41|OwnerIndex=831|IndexInSheet=21|OwnerPartId=-1|Location.X=264|Location.Y=112|Color=8388608|FontID=1|IsHidden=T|Text=Not|Name=Military Standard
|RECORD=41|OwnerIndex=831|IndexInSheet=22|OwnerPartId=-1|Location.X=264|Location.Y=112|Color=8388608|FontID=1|IsHidden=T|Text=Thick Film|Name=Resistor Type
|RECORD=41|OwnerIndex=831|IndexInSheet=23|OwnerPartId=-1|Location.X=264|Location.Y=112|Color=8388608|FontID=1|IsHidden=T|Text=100ppm/°C|Name=Temperature Coefficient
|RECORD=41|OwnerIndex=831|IndexInSheet=24|OwnerPartId=-1|Location.X=264|Location.Y=112|Color=8388608|FontID=1|IsHidden=T|Text=2|Name=Number of Terminations
|RECORD=41|OwnerIndex=831|IndexInSheet=25|OwnerPartId=-1|Location.X=264|Location.Y=112|Color=8388608|FontID=1|IsHidden=T|Text=-55°C|Name=Min Operating Temperature
|RECORD=41|OwnerIndex=831|IndexInSheet=26|OwnerPartId=-1|Location.X=264|Location.Y=112|Color=8388608|FontID=1|IsHidden=T|Text=155°C|Name=Max Operating Temperature
|RECORD=41|OwnerIndex=831|IndexInSheet=27|OwnerPartId=-1|Location.X=264|Location.Y=112|Color=8388608|FontID=1|IsHidden=T|Text=63mW|Name=Power Rating
|RECORD=41|OwnerIndex=831|IndexInSheet=28|OwnerPartId=-1|Location.X=264|Location.Y=112|Color=8388608|FontID=1|IsHidden=T|Text=0.5mm|Name=Depth
|RECORD=41|OwnerIndex=831|IndexInSheet=29|OwnerPartId=-1|Location.X=264|Location.Y=112|Color=8388608|FontID=1|IsHidden=T|Text=Automotive AEC-Q200|Name=Features
|RECORD=41|OwnerIndex=831|IndexInSheet=30|OwnerPartId=-1|Location.X=264|Location.Y=112|Color=8388608|FontID=1|IsHidden=T|Text=Tape and Reel|Name=Packaging
|RECORD=41|OwnerIndex=831|IndexInSheet=31|OwnerPartId=-1|Location.X=264|Location.Y=112|Color=8388608|FontID=1|IsHidden=T|Text=1005|Name=Case Code (Metric)
|RECORD=41|OwnerIndex=831|IndexInSheet=32|OwnerPartId=-1|Location.X=264|Location.Y=112|Color=8388608|FontID=1|IsHidden=T|Text=Surface Mount|Name=Mount
|RECORD=41|OwnerIndex=831|IndexInSheet=33|OwnerPartId=-1|Location.X=264|Location.Y=112|Color=8388608|FontID=1|IsHidden=T|Text=Tin|Name=Contact Plating
|RECORD=41|OwnerIndex=831|IndexInSheet=34|OwnerPartId=-1|Location.X=264|Location.Y=112|Color=8388608|FontID=1|IsHidden=T|Text=63mW|Name=Max Power Dissipation
|RECORD=41|OwnerIndex=831|IndexInSheet=35|OwnerPartId=-1|Location.X=264|Location.Y=112|Color=8388608|FontID=1|IsHidden=T|Text=0402|Name=Case/Package
|RECORD=41|OwnerIndex=831|IndexInSheet=36|OwnerPartId=-1|Location.X=264|Location.Y=112|Color=8388608|FontID=1|IsHidden=T|Text=0402|Name=Case Code (Imperial)
|RECORD=41|OwnerIndex=831|IndexInSheet=37|OwnerPartId=-1|Location.X=264|Location.Y=112|Color=8388608|FontID=1|IsHidden=T|Text=RMCF|Name=Series
|RECORD=34|OwnerIndex=831|IndexInSheet=-1|OwnerPartId=-1|Location.X=276|Location.Y=84|Color=8388608|FontID=1|Text=R18|Name=Designator|ReadOnlyState=1
|RECORD=41|OwnerIndex=831|IndexInSheet=-1|OwnerPartId=1|Location.X=276|Location.Y=74|Color=8388608|FontID=1|Text=1k|Name=Comment
|RECORD=44|OwnerIndex=831
|RECORD=45|OwnerIndex=874|IndexInSheet=-1|UseComponentLibrary=T|ModelName=FP-RMCF0402-MFG|ModelType=PCBLIB|DatafileCount=1|ModelDatafileEntity0=FP-RMCF0402-MFG|ModelDatafileKind0=PCBLib|IsCurrent=T|DatalinksLocked=T|DatabaseDatalinksLocked=T
|RECORD=46|OwnerIndex=875
|RECORD=48|OwnerIndex=875
|RECORD=45|OwnerIndex=874|IndexInSheet=-1|UseComponentLibrary=T|ModelName=FP-RMCF0402-IPC_C|ModelType=PCBLIB|DatafileCount=1|ModelDatafileEntity0=FP-RMCF0402-IPC_C|ModelDatafileKind0=PCBLib|DatalinksLocked=T|DatabaseDatalinksLocked=T
|RECORD=46|OwnerIndex=878
|RECORD=48|OwnerIndex=878
|RECORD=45|OwnerIndex=874|IndexInSheet=-1|UseComponentLibrary=T|ModelName=FP-RMCF0402-IPC_B|ModelType=PCBLIB|DatafileCount=1|ModelDatafileEntity0=FP-RMCF0402-IPC_B|ModelDatafileKind0=PCBLib|DatalinksLocked=T|DatabaseDatalinksLocked=T
|RECORD=46|OwnerIndex=881
|RECORD=48|OwnerIndex=881
|RECORD=45|OwnerIndex=874|IndexInSheet=-1|UseComponentLibrary=T|ModelName=FP-RMCF0402-IPC_A|ModelType=PCBLIB|DatafileCount=1|ModelDatafileEntity0=FP-RMCF0402-IPC_A|ModelDatafileKind0=PCBLib|DatalinksLocked=T|DatabaseDatalinksLocked=T
|RECORD=46|OwnerIndex=884
|RECORD=48|OwnerIndex=884
|RECORD=25|IndexInSheet=67|OwnerPartId=-1|Location.X=200|Location.Y=40|Justification=2|Color=128|FontID=1|Text=ANT_DET
|RECORD=25|IndexInSheet=68|OwnerPartId=-1|Location.X=350|Location.Y=40|Justification=2|Color=128|FontID=1|Text=ANT_SHORT_N
|RECORD=17|IndexInSheet=69|OwnerPartId=-1|Style=2|ShowNetName=T|Location.X=150|Location.Y=110|Orientation=1|Color=128|FontID=1|Text=+3V3
|RECORD=17|IndexInSheet=70|OwnerPartId=-1|Style=2|ShowNetName=T|Location.X=270|Location.Y=110|Orientation=1|Color=128|FontID=1|Text=+3V3
|RECORD=14|IndexInSheet=71|OwnerPartId=-1|Location.X=120|Location.Y=30|Corner.X=440|Corner.Y=140|Color=128|AreaColor=11599871
|RECORD=4|IndexInSheet=72|OwnerPartId=-1|Location.X=190|Location.Y=140|Color=8388608|FontID=4|Text=Buffer Pullups
|RECORD=1|LibReference=AMP-OPA-LM7121-5|ComponentDescription=micropower Rail-to-Rail Input and Output Operational Amplifier, 5-pin SC-70, Pb-Free|PartCount=2|DisplayModeCount=1|IndexInSheet=73|OwnerPartId=-1|Location.X=520|Location.Y=440|CurrentPartId=1|LibraryPath=*|SourceLibraryName=Altium Content Vault|TargetFileName=*|AreaColor=11599871|Color=128|PartIDLocked=F|DesignItemId=CMP-0055-01065-3|AllPinCount=5
|RECORD=2|OwnerIndex=893|OwnerPartId=1|FormalType=1|Electrical=7|PinConglomerate=51|PinLength=20|Location.X=540|Location.Y=400|Name=V-|Designator=2|PinPropagationDelay=0.000000E+000
|RECORD=2|OwnerIndex=893|OwnerPartId=1|FormalType=1|PinConglomerate=50|PinLength=20|Location.X=520|Location.Y=410|Name=IN+|Designator=3|PinPropagationDelay=0.000000E+000
|RECORD=2|OwnerIndex=893|OwnerPartId=1|FormalType=1|PinConglomerate=50|PinLength=20|Location.X=520|Location.Y=430|Name=IN-|Designator=4|PinPropagationDelay=0.000000E+000
|RECORD=2|OwnerIndex=893|OwnerPartId=1|FormalType=1|Electrical=7|PinConglomerate=49|PinLength=20|Location.X=540|Location.Y=440|Name=V+|Designator=5|PinPropagationDelay=0.000000E+000
|RECORD=2|OwnerIndex=893|OwnerPartId=1|FormalType=1|Electrical=2|PinConglomerate=48|PinLength=20|Location.X=560|Location.Y=420|Name=OUT|Designator=1|PinPropagationDelay=0.000000E+000
|RECORD=13|OwnerIndex=893|IsNotAccesible=T|IndexInSheet=5|OwnerPartId=1|Location.X=520|Location.Y=440|Corner.X=560|Corner.Y=420|LineWidth=1|Color=16711680
|RECORD=13|OwnerIndex=893|IsNotAccesible=T|IndexInSheet=6|OwnerPartId=1|Location.X=520|Location.Y=400|Corner.X=560|Corner.Y=420|LineWidth=1|Color=16711680
|RECORD=13|OwnerIndex=893|IsNotAccesible=T|IndexInSheet=7|OwnerPartId=1|Location.X=520|Location.Y=440|Corner.X=520|Corner.Y=400|LineWidth=1|Color=16711680
|RECORD=13|OwnerIndex=893|IsNotAccesible=T|IndexInSheet=8|OwnerPartId=1|Location.X=524|Location.Y=430|Corner.X=530|Corner.Y=430|LineWidth=1|Color=16711680
|RECORD=13|OwnerIndex=893|IsNotAccesible=T|IndexInSheet=9|OwnerPartId=1|Location.X=524|Location.Y=410|Corner.X=530|Corner.Y=410|LineWidth=1|Color=16711680
|RECORD=13|OwnerIndex=893|IsNotAccesible=T|IndexInSheet=10|OwnerPartId=1|Location.X=527|Location.Y=413|Corner.X=527|Corner.Y=407|LineWidth=1|Color=16711680
|RECORD=13|OwnerIndex=893|IsNotAccesible=T|IndexInSheet=11|OwnerPartId=1|Location.X=540|Location.Y=440|Corner.X=540|Corner.Y=430|LineWidth=1|Color=16711680
|RECORD=13|OwnerIndex=893|IsNotAccesible=T|IndexInSheet=12|OwnerPartId=1|Location.X=540|Location.Y=410|Corner.X=540|Corner.Y=400|LineWidth=1|Color=16711680
|RECORD=41|OwnerIndex=893|IndexInSheet=13|OwnerPartId=-1|Location.X=498|Location.Y=462|Color=8388608|FontID=3|IsHidden=T|Text=http://www.ti.com/general/docs/lit/getliterature.tsp?genericPartNumber=LPV511&fileType=pdf|Name=ComponentLink1URL
|RECORD=41|OwnerIndex=893|IndexInSheet=14|OwnerPartId=-1|Location.X=498|Location.Y=462|Color=8388608|FontID=1|IsHidden=T|Text=MO-203-AA|Name=Code_JEDEC
|RECORD=41|OwnerIndex=893|IndexInSheet=15|OwnerPartId=-1|Location.X=498|Location.Y=462|Color=8388608|FontID=1|IsHidden=T|Text=Y|Name=RoHS
|RECORD=41|OwnerIndex=893|IndexInSheet=16|OwnerPartId=-1|Location.X=498|Location.Y=462|Color=8388608|FontID=1|IsHidden=T|Text=SOT353-5|Name=Code_IPC
|RECORD=41|OwnerIndex=893|IndexInSheet=17|OwnerPartId=-1|Location.X=498|Location.Y=462|Color=8388608|FontID=1|IsHidden=T|Text=5|Name=PinCount
|RECORD=41|OwnerIndex=893|IndexInSheet=18|OwnerPartId=-1|Location.X=498|Location.Y=462|Color=8388608|FontID=1|IsHidden=T|Text=Molded SC-70, 2 x 1.25 x .9mm, 5 Lead, 0.65mm Pitch|Name=PackageDescription
|RECORD=41|OwnerIndex=893|IndexInSheet=19|OwnerPartId=-1|Location.X=498|Location.Y=462|Color=8388608|FontID=1|IsHidden=T|Name=High-Reliability
|RECORD=41|OwnerIndex=893|IndexInSheet=20|OwnerPartId=-1|Location.X=498|Location.Y=462|Color=8388608|FontID=1|IsHidden=T|Text=Amplifiers|Name=CompType
|RECORD=41|OwnerIndex=893|IndexInSheet=21|OwnerPartId=-1|Location.X=498|Location.Y=462|Color=8388608|FontID=1|IsHidden=T|Text=Datasheet URL|Name=ComponentLink1Description
|RECORD=41|OwnerIndex=893|IndexInSheet=22|OwnerPartId=-1|Location.X=498|Location.Y=462|Color=8388608|FontID=1|IsHidden=T|Text=DCK0005A|Name=Package Reference
|RECORD=41|OwnerIndex=893|IndexInSheet=23|OwnerPartId=-1|Location.X=498|Location.Y=462|Color=8388608|FontID=1|IsHidden=T|Name=PartNumber
|RECORD=41|OwnerIndex=893|IndexInSheet=24|OwnerPartId=-1|Location.X=498|Location.Y=462|Color=8388608|FontID=1|IsHidden=T|Text=Texas Instruments|Name=Manufacturer
|RECORD=41|OwnerIndex=893|IndexInSheet=25|OwnerPartId=-1|Location.X=498|Location.Y=462|Color=8388608|FontID=1|IsHidden=T|Text=A91*XTT|Name=PackageTopMarking
|RECORD=41|OwnerIndex=893|IndexInSheet=26|OwnerPartId=-1|Location.X=498|Location.Y=462|Color=8388608|FontID=1|IsHidden=T|Text=Y|Name=PowerWise
|RECORD=41|OwnerIndex=893|IndexInSheet=27|OwnerPartId=-1|Location.X=498|Location.Y=462|Color=8388608|FontID=1|IsHidden=T|Text=SC-88A|Name=Code_JEITA
|RECORD=34|OwnerIndex=893|IndexInSheet=-1|OwnerPartId=-1|Location.X=582|Location.Y=441|Color=8388608|FontID=1|Text=U4|Name=Designator|ReadOnlyState=1
|RECORD=41|OwnerIndex=893|IndexInSheet=-1|OwnerPartId=-1|Location.X=582|Location.Y=431|Color=8388608|FontID=1|Text=LPV511MGX/NOPB|Name=Comment
|RECORD=44|OwnerIndex=893
|RECORD=45|OwnerIndex=929|IndexInSheet=-1|Description=SOT23, 5-Leads, Body 2.15x1.4mm, Pitch 0.65mm, IPC Medium Density|UseComponentLibrary=T|ModelName=DCK0005A_N|ModelType=PCBLIB|DatafileCount=1|ModelDatafileEntity0=DCK0005A_N|ModelDatafileKind0=PCBLib|IsCurrent=T|DatalinksLocked=T|DatabaseDatalinksLocked=T
|RECORD=46|OwnerIndex=930
|RECORD=48|OwnerIndex=930
|RECORD=41|OwnerIndex=932|IndexInSheet=-1|OwnerPartId=-1|Color=8388608|FontID=1|IsHidden=T|Text=2D|Name=Available Preview Images
|RECORD=45|OwnerIndex=929|IndexInSheet=-1|Description=SOT23, 5-Leads, Body 2.15x1.4mm, Pitch 0.65mm, IPC High Density|UseComponentLibrary=T|ModelName=DCK0005A_L|ModelType=PCBLIB|DatafileCount=1|ModelDatafileEntity0=DCK0005A_L|ModelDatafileKind0=PCBLib|DatalinksLocked=T|DatabaseDatalinksLocked=T
|RECORD=46|OwnerIndex=934
|RECORD=48|OwnerIndex=934
|RECORD=41|OwnerIndex=936|IndexInSheet=-1|OwnerPartId=-1|Color=8388608|FontID=1|IsHidden=T|Text=2D|Name=Available Preview Images
|RECORD=45|OwnerIndex=929|IndexInSheet=-1|Description=SOT23, 5-Leads, Body 2.15x1.4mm, Pitch 0.65mm, IPC Low Density|UseComponentLibrary=T|ModelName=DCK0005A_M|ModelType=PCBLIB|DatafileCount=1|ModelDatafileEntity0=DCK0005A_M|ModelDatafileKind0=PCBLib|DatalinksLocked=T|DatabaseDatalinksLocked=T
|RECORD=46|OwnerIndex=938
|RECORD=48|OwnerIndex=938
|RECORD=41|OwnerIndex=940|IndexInSheet=-1|OwnerPartId=-1|Color=8388608|FontID=1|IsHidden=T|Text=2D|Name=Available Preview Images
|RECORD=27|IndexInSheet=74|OwnerPartId=-1|LineWidth=1|Color=8388608|LocationCount=2|X1=560|Y1=490|X2=540|Y2=490
|RECORD=27|IndexInSheet=75|OwnerPartId=-1|LineWidth=1|Color=8388608|LocationCount=2|X1=540|Y1=460|X2=540|Y2=490
|RECORD=27|IndexInSheet=76|OwnerPartId=-1|LineWidth=1|Color=8388608|LocationCount=2|X1=400|Y1=300|X2=400|Y2=280
|RECORD=27|IndexInSheet=77|OwnerPartId=-1|LineWidth=1|Color=8388608|LocationCount=2|X1=400|Y1=300|X2=350|Y2=300
|RECORD=27|IndexInSheet=78|OwnerPartId=-1|LineWidth=1|Color=8388608|LocationCount=2|X1=460|Y1=510|X2=460|Y2=560
|RECORD=27|IndexInSheet=79|OwnerPartId=-1|LineWidth=1|Color=8388608|LocationCount=2|X1=700|Y1=290|X2=730|Y2=290
|RECORD=27|IndexInSheet=80|OwnerPartId=-1|LineWidth=1|Color=8388608|LocationCount=2|X1=840|Y1=290|X2=830|Y2=290
|RECORD=27|IndexInSheet=81|OwnerPartId=-1|LineWidth=1|Color=8388608|LocationCount=2|X1=680|Y1=490|X2=730|Y2=490
|RECORD=27|IndexInSheet=82|OwnerPartId=-1|LineWidth=1|Color=8388608|LocationCount=2|X1=580|Y1=420|X2=730|Y2=420
|RECORD=27|IndexInSheet=83|OwnerPartId=-1|LineWidth=1|Color=8388608|LocationCount=2|X1=800|Y1=420|X2=870|Y2=420
|RECORD=27|IndexInSheet=84|OwnerPartId=-1|LineWidth=1|Color=8388608|LocationCount=2|X1=870|Y1=350|X2=800|Y2=350
|RECORD=27|IndexInSheet=85|OwnerPartId=-1|LineWidth=1|Color=8388608|LocationCount=4|X1=730|Y1=350|X2=610|Y2=350|X3=610|Y3=300|X4=490|Y4=300
|RECORD=27|IndexInSheet=86|OwnerPartId=-1|LineWidth=1|Color=8388608|LocationCount=2|X1=290|Y1=270|X2=290|Y2=300
|RECORD=27|IndexInSheet=87|OwnerPartId=-1|LineWidth=1|Color=8388608|LocationCount=2|X1=290|Y1=300|X2=310|Y2=300
|RECORD=27|IndexInSheet=88|OwnerPartId=-1|LineWidth=1|Color=8388608|LocationCount=2|X1=400|Y1=340|X2=400|Y2=300
|RECORD=27|IndexInSheet=89|OwnerPartId=-1|LineWidth=1|Color=8388608|LocationCount=2|X1=280|Y1=300|X2=280|Y2=340
|RECORD=27|IndexInSheet=90|OwnerPartId=-1|LineWidth=1|Color=8388608|LocationCount=2|X1=200|Y1=40|X2=150|Y2=40
|RECORD=27|IndexInSheet=91|OwnerPartId=-1|LineWidth=1|Color=8388608|LocationCount=2|X1=350|Y1=40|X2=270|Y2=40
|RECORD=27|IndexInSheet=92|OwnerPartId=-1|LineWidth=1|Color=8388608|LocationCount=3|X1=460|Y1=400|X2=460|Y2=410|X3=460|Y3=440
|RECORD=27|IndexInSheet=93|OwnerPartId=-1|LineWidth=1|Color=8388608|LocationCount=4|X1=500|Y1=430|X2=490|Y2=430|X3=490|Y3=300|X4=400|Y4=300
|RECORD=27|IndexInSheet=94|OwnerPartId=-1|LineWidth=1|Color=8388608|LocationCount=2|X1=500|Y1=410|X2=460|Y2=410
|RECORD=41|IndexInSheet=95|OwnerPartId=-1|Color=8388608|FontID=1|IsHidden=T|Text=|Name=SPICEModelCacheELOCFEDZ|ReadOnlyState=3
|RECORD=1|LibReference=CN-1P-M-R3|ComponentDescription=Ultra Small Coaxial Connector, 6 GHz, -40 to 90 degC, 3-Pin SMD, RoHS, Bulk|PartCount=2|DisplayModeCount=1|IndexInSheet=96|OwnerPartId=-1|Location.X=130|Location.Y=270|Orientation=2|CurrentPartId=1|LibraryPath=*|SourceLibraryName=Altium Content Vault|TargetFileName=*|AreaColor=11599871|Color=128|PartIDLocked=T|DesignItemId=CMP-2000-05153-1|AllPinCount=3
|RECORD=2|OwnerIndex=964|OwnerPartId=1|FormalType=1|Electrical=4|PinConglomerate=48|PinLength=20|Location.X=130|Location.Y=300|Name=3|Designator=3|PinPropagationDelay=0.000000E+000
|RECORD=2|OwnerIndex=964|OwnerPartId=1|FormalType=1|Electrical=4|PinConglomerate=48|PinLength=20|Location.X=130|Location.Y=290|Name=2|Designator=2|PinPropagationDelay=0.000000E+000
|RECORD=2|OwnerIndex=964|OwnerPartId=1|FormalType=1|Electrical=4|PinConglomerate=48|PinLength=20|Location.X=130|Location.Y=280|Name=1|Designator=1|PinPropagationDelay=0.000000E+000
|RECORD=14|OwnerIndex=964|IsNotAccesible=T|IndexInSheet=3|OwnerPartId=1|Location.X=110|Location.Y=270|Corner.X=130|Corner.Y=310|LineWidth=1|Color=16711680|AreaColor=16777215
|RECORD=6|OwnerIndex=964|IsNotAccesible=T|IndexInSheet=4|OwnerPartId=1|LineWidth=1|Color=16711680|LocationCount=2|X1=130|Y1=290|X2=123|Y2=290
|RECORD=8|OwnerIndex=964|IsNotAccesible=T|IndexInSheet=5|OwnerPartId=1|Location.X=120|Location.Y=290|Radius=3|SecondaryRadius=3|LineWidth=1|Color=16711680|AreaColor=16711680|IsSolid=T|Transparent=T
|RECORD=6|OwnerIndex=964|IsNotAccesible=T|IndexInSheet=6|OwnerPartId=1|LineWidth=1|Color=16711680|LocationCount=2|X1=130|Y1=300|X2=123|Y2=300
|RECORD=8|OwnerIndex=964|IsNotAccesible=T|IndexInSheet=7|OwnerPartId=1|Location.X=120|Location.Y=300|Radius=3|SecondaryRadius=3|LineWidth=1|Color=16711680|AreaColor=16711680|IsSolid=T|Transparent=T
|RECORD=6|OwnerIndex=964|IsNotAccesible=T|IndexInSheet=8|OwnerPartId=1|LineWidth=1|Color=16711680|LocationCount=2|X1=130|Y1=280|X2=123|Y2=280
|RECORD=14|OwnerIndex=964|IsNotAccesible=T|IndexInSheet=9|OwnerPartId=1|Location.X=117|Location.Y=277|Corner.X=123|Corner.Y=283|LineWidth=1|Color=16711680|AreaColor=16711680|IsSolid=T
|RECORD=41|OwnerIndex=964|IndexInSheet=10|OwnerPartId=-1|Location.X=110|Location.Y=310|Color=8388608|FontID=3|IsHidden=T|Text=https://www.hirose.com|Name=Manufacturer URL
|RECORD=41|OwnerIndex=964|IndexInSheet=11|OwnerPartId=-1|Location.X=110|Location.Y=310|Color=8388608|FontID=1|IsHidden=T|Text=CoaxialConnectors(RF)|Name=Family
|RECORD=41|OwnerIndex=964|IndexInSheet=12|OwnerPartId=-1|Location.X=110|Location.Y=310|Color=8388608|FontID=1|IsHidden=T|Text=U.FL|Name=Connector Style
|RECORD=41|OwnerIndex=964|IndexInSheet=13|OwnerPartId=-1|Location.X=110|Location.Y=310|Color=8388608|FontID=1|IsHidden=T|Text=50Ohm|Name=Impedance
|RECORD=41|OwnerIndex=964|IndexInSheet=14|OwnerPartId=-1|Location.X=110|Location.Y=310|Color=8388608|FontID=1|IsHidden=T|Text=Snap-On|Name=Fastening Type
|RECORD=41|OwnerIndex=964|IndexInSheet=15|OwnerPartId=-1|Location.X=110|Location.Y=310|Color=8388608|FontID=1|IsHidden=T|Text=LiquidCrystalPolymer(LCP)|Name=Dielectric Material
|RECORD=41|OwnerIndex=964|IndexInSheet=16|OwnerPartId=-1|Location.X=110|Location.Y=310|Color=8388608|FontID=1|IsHidden=T|Text=UltraMiniatureCoaxial|Name=Minimum Quantity
|RECORD=41|OwnerIndex=964|IndexInSheet=17|OwnerPartId=-1|Location.X=110|Location.Y=310|Color=8388608|FontID=1|IsHidden=T|Text=U.FL|Name=Unit PriceUSD
|RECORD=41|OwnerIndex=964|IndexInSheet=18|OwnerPartId=-1|Location.X=110|Location.Y=310|Color=8388608|FontID=1|IsHidden=T|Text=U.FL|Name=Series
|RECORD=41|OwnerIndex=964|IndexInSheet=19|OwnerPartId=-1|Location.X=110|Location.Y=310|Color=8388608|FontID=1|IsHidden=T|Text=U.FL-R-SMT|Name=Package Reference
|RECORD=41|OwnerIndex=964|IndexInSheet=20|OwnerPartId=-1|Location.X=110|Location.Y=310|Color=8388608|FontID=1|IsHidden=T|Text=U.FLSeries|Name=Online Catalog
|RECORD=41|OwnerIndex=964|IndexInSheet=21|OwnerPartId=-1|Location.X=110|Location.Y=310|Color=8388608|FontID=1|IsHidden=T|Text=HiroseU.FLSeries|Name=Featured Product
|RECORD=41|OwnerIndex=964|IndexInSheet=22|OwnerPartId=-1|Location.X=110|Location.Y=310|Color=8388608|FontID=1|IsHidden=T|Text=6GHz|Name=Frequency - Max
|RECORD=41|OwnerIndex=964|IndexInSheet=23|OwnerPartId=-1|Location.X=110|Location.Y=310|Color=8388608|FontID=1|IsHidden=T|Text=Bulk|Name=Packaging
|RECORD=41|OwnerIndex=964|IndexInSheet=24|OwnerPartId=-1|Location.X=110|Location.Y=310|Color=8388608|FontID=1|IsHidden=T|Text=H122041
U.FL-R-SMT-1(01)-ND|Name=Other Names
|RECORD=41|OwnerIndex=964|IndexInSheet=25|OwnerPartId=-1|Location.X=110|Location.Y=310|Color=8388608|FontID=1|IsHidden=T|Text=100|Name=Standard Package
|RECORD=41|OwnerIndex=964|IndexInSheet=26|OwnerPartId=-1|Location.X=110|Location.Y=310|Color=8388608|FontID=1|IsHidden=T|Text=SurfaceMount|Name=Mounting Type
|RECORD=41|OwnerIndex=964|IndexInSheet=27|OwnerPartId=-1|Location.X=110|Location.Y=310|Color=8388608|FontID=1|IsHidden=T|Text=Solder|Name=Contact Termination
|RECORD=41|OwnerIndex=964|IndexInSheet=28|OwnerPartId=-1|Location.X=110|Location.Y=310|Color=8388608|FontID=1|IsHidden=T|Text=Bulk|Name=Quantity Available
|RECORD=41|OwnerIndex=964|IndexInSheet=29|OwnerPartId=-1|Location.X=110|Location.Y=310|Color=8388608|FontID=1|IsHidden=T|Text=Silver|Name=Housing Color
|RECORD=41|OwnerIndex=964|IndexInSheet=30|OwnerPartId=-1|Location.X=110|Location.Y=310|Color=8388608|FontID=1|IsHidden=T|Text=PhosphorBronze|Name=Body Material
|RECORD=41|OwnerIndex=964|IndexInSheet=31|OwnerPartId=-1|Location.X=110|Location.Y=310|Color=8388608|FontID=1|IsHidden=T|Text=3-Pin Surface Mount Device, Body 2.6 x 2.6 mm|Name=Package Description
|RECORD=41|OwnerIndex=964|IndexInSheet=32|OwnerPartId=-1|Location.X=110|Location.Y=310|Color=8388608|FontID=1|IsHidden=T|Text=Jack,MalePin|Name=Connector Type
|RECORD=41|OwnerIndex=964|IndexInSheet=33|OwnerPartId=-1|Location.X=110|Location.Y=310|Color=8388608|FontID=1|IsHidden=T|Text=Connectors,Interconnects|Name=Category
|RECORD=41|OwnerIndex=964|IndexInSheet=34|OwnerPartId=-1|Location.X=110|Location.Y=310|Color=8388608|FontID=1|IsHidden=T|Text=Silver|Name=Body Finish
|RECORD=41|OwnerIndex=964|IndexInSheet=35|OwnerPartId=-1|Location.X=110|Location.Y=310|Color=8388608|FontID=1|IsHidden=T|Text=-40degC~90degC|Name=Operating Temperature
|RECORD=41|OwnerIndex=964|IndexInSheet=36|OwnerPartId=-1|Location.X=110|Location.Y=310|Color=8388608|FontID=1|IsHidden=T|Text=PhosphorBronze|Name=Center Contact Material
|RECORD=41|OwnerIndex=964|IndexInSheet=37|OwnerPartId=-1|Location.X=110|Location.Y=310|Color=8388608|FontID=1|IsHidden=T|Text=U.FLSeries|Name=Dynamic Catalog
|RECORD=41|OwnerIndex=964|IndexInSheet=38|OwnerPartId=-1|Location.X=110|Location.Y=310|Color=8388608|FontID=3|IsHidden=T|Text=https://datasheet.ciiva.com/26945/getdatasheetpartid-475239-26945414.pdf|Name=Datasheet URL
|RECORD=41|OwnerIndex=964|IndexInSheet=39|OwnerPartId=-1|Location.X=110|Location.Y=310|Color=8388608|FontID=1|IsHidden=T|Text=Hirose Electric|Name=Manufacturer
|RECORD=41|OwnerIndex=964|IndexInSheet=40|OwnerPartId=-1|Location.X=110|Location.Y=310|Color=8388608|FontID=1|IsHidden=T|Text=Feb-09|Name=Datasheet Version
|RECORD=41|OwnerIndex=964|IndexInSheet=41|OwnerPartId=-1|Location.X=110|Location.Y=310|Color=8388608|FontID=1|IsHidden=T|Text=Gold|Name=Center Contact Plating
|RECORD=41|OwnerIndex=964|IndexInSheet=42|OwnerPartId=-1|Location.X=110|Location.Y=310|Color=8388608|FontID=1|IsHidden=T|Text=Solder|Name=Shield Termination
|RECORD=34|OwnerIndex=964|IndexInSheet=-1|OwnerPartId=-1|Location.X=110|Location.Y=310|Color=8388608|FontID=1|Text=P1|Name=Designator|ReadOnlyState=1
|RECORD=41|OwnerIndex=964|IndexInSheet=-1|OwnerPartId=-1|Location.X=110|Location.Y=260|Color=8388608|FontID=1|Text=U.FL-R-SMT-1(01)|Name=Comment
|RECORD=44|OwnerIndex=964
|RECORD=45|OwnerIndex=1013|IndexInSheet=-1|Description=SMT, 3-Leads, Body 2.6x2.6mm|UseComponentLibrary=T|ModelName=HRS-U.FL-R-SMT-3_V|ModelType=PCBLIB|IsCurrent=T|DatalinksLocked=T|DatabaseDatalinksLocked=T
|RECORD=46|OwnerIndex=1014
|RECORD=48|OwnerIndex=1014
|RECORD=41|OwnerIndex=1016|IndexInSheet=-1|OwnerPartId=-1|Color=8388608|FontID=1|IsHidden=T|Text=2D|Name=Available Preview Images
|RECORD=27|IndexInSheet=97|OwnerPartId=-1|LineWidth=1|Color=8388608|LocationCount=4|X1=150|Y1=290|X2=170|Y2=290|X3=170|Y3=280|X4=170|Y4=230
|RECORD=27|IndexInSheet=98|OwnerPartId=-1|LineWidth=1|Color=8388608|LocationCount=2|X1=150|Y1=280|X2=170|Y2=280
|RECORD=27|IndexInSheet=99|OwnerPartId=-1|LineWidth=1|Color=8388608|LocationCount=3|X1=150|Y1=300|X2=280|Y2=300|X3=290|Y3=300
|RECORD=17|IndexInSheet=100|OwnerPartId=-1|Style=1|ShowNetName=T|Location.X=200|Location.Y=40|Color=255|FontID=1|Text=ANT_DET|IsCrossSheetConnector=T
|RECORD=17|IndexInSheet=101|OwnerPartId=-1|Style=1|ShowNetName=T|Location.X=680|Location.Y=490|Orientation=2|Color=255|FontID=1|Text=ANT_OFF|IsCrossSheetConnector=T
|RECORD=17|IndexInSheet=102|OwnerPartId=-1|Style=1|ShowNetName=T|Location.X=350|Location.Y=40|Color=255|FontID=1|Text=ANT_SHORT_N|IsCrossSheetConnector=T
|RECORD=27|IndexInSheet=103|OwnerPartId=-1|LineWidth=1|Color=8388608|LocationCount=2|X1=290|Y1=180|X2=290|Y2=170
|RECORD=17|IndexInSheet=104|OwnerPartId=-1|Style=1|ShowNetName=T|Location.X=190|Location.Y=370|Orientation=2|Color=255|FontID=1|Text=RF_IN|IsCrossSheetConnector=T
|RECORD=27|IndexInSheet=105|OwnerPartId=-1|LineWidth=1|Color=8388608|LocationCount=3|X1=190|Y1=370|X2=280|Y2=370|X3=280|Y3=360
|RECORD=1|LibReference=1029c3af85768c4190bb7ad29bc67b5|ComponentDescription=RES Thick Film, 22.6O, 1%, 1.5W, 100ppm/°C, 1218|PartCount=2|DisplayModeCount=1|IndexInSheet=106|OwnerPartId=-1|Location.X=400|Location.Y=340|Orientation=1|CurrentPartId=1|LibraryPath=*|SourceLibraryName=Altium Content Vault|TargetFileName=*|AreaColor=11599871|Color=128|PartIDLocked=T|DesignItemId=CMP-02407-011337-1|AllPinCount=2
|RECORD=2|OwnerIndex=1027|OwnerPartId=1|Electrical=4|PinConglomerate=51|PinLength=20|Location.X=400|Location.Y=360|Name=1|Designator=1|PinPropagationDelay=0.000000E+000
|RECORD=2|OwnerIndex=1027|OwnerPartId=1|Electrical=4|PinConglomerate=49|PinLength=20|Location.X=400|Location.Y=390|Name=2|Designator=2|PinPropagationDelay=0.000000E+000
|RECORD=13|OwnerIndex=1027|IsNotAccesible=T|IndexInSheet=2|OwnerPartId=1|Location.X=400|Location.Y=360|Corner.X=395|Corner.Y=363|LineWidth=1|Color=16711680
|RECORD=13|OwnerIndex=1027|IsNotAccesible=T|IndexInSheet=3|OwnerPartId=1|Location.X=395|Location.Y=363|Corner.X=405|Corner.Y=368|LineWidth=1|Color=16711680
|RECORD=13|OwnerIndex=1027|IsNotAccesible=T|IndexInSheet=4|OwnerPartId=1|Location.X=405|Location.Y=368|Corner.X=395|Corner.Y=373|LineWidth=1|Color=16711680
|RECORD=13|OwnerIndex=1027|IsNotAccesible=T|IndexInSheet=5|OwnerPartId=1|Location.X=395|Location.Y=373|Corner.X=405|Corner.Y=378|LineWidth=1|Color=16711680
|RECORD=13|OwnerIndex=1027|IsNotAccesible=T|IndexInSheet=6|OwnerPartId=1|Location.X=405|Location.Y=378|Corner.X=395|Corner.Y=383|LineWidth=1|Color=16711680
|RECORD=13|OwnerIndex=1027|IsNotAccesible=T|IndexInSheet=7|OwnerPartId=1|Location.X=395|Location.Y=383|Corner.X=405|Corner.Y=388|LineWidth=1|Color=16711680
|RECORD=13|OwnerIndex=1027|IsNotAccesible=T|IndexInSheet=8|OwnerPartId=1|Location.X=405|Location.Y=388|Corner.X=400|Corner.Y=390|LineWidth=1|Color=16711680
|RECORD=13|OwnerIndex=1027|IsNotAccesible=T|IndexInSheet=9|OwnerPartId=1|Location.X=400|Location.Y=360|Corner.X=400|Corner.Y=357|LineWidth=1|Color=16711680
|RECORD=13|OwnerIndex=1027|IsNotAccesible=T|IndexInSheet=10|OwnerPartId=1|Location.X=400|Location.Y=390|Corner.X=400|Corner.Y=393|LineWidth=1|Color=16711680
|RECORD=41|OwnerIndex=1027|IndexInSheet=11|OwnerPartId=-1|Location.X=394|Location.Y=412|Color=8388608|FontID=1|IsHidden=T|Text=100ppm/°C|Name=Temperature Coefficient
|RECORD=41|OwnerIndex=1027|IndexInSheet=12|OwnerPartId=-1|Location.X=394|Location.Y=412|Color=8388608|FontID=1|IsHidden=T|Text=22.6R|Name=Resistance
|RECORD=41|OwnerIndex=1027|IndexInSheet=13|OwnerPartId=-1|Location.X=394|Location.Y=412|Color=8388608|FontID=1|IsHidden=T|Text=-55°C|Name=Min Operating Temperature
|RECORD=41|OwnerIndex=1027|IndexInSheet=14|OwnerPartId=-1|Location.X=394|Location.Y=412|Color=8388608|FontID=1|IsHidden=T|Text=2|Name=Number of Terminations
|RECORD=41|OwnerIndex=1027|IndexInSheet=15|OwnerPartId=-1|Location.X=394|Location.Y=412|Color=8388608|FontID=1|IsHidden=T|Text=0.122inch|Name=Length
|RECORD=41|OwnerIndex=1027|IndexInSheet=16|OwnerPartId=-1|Location.X=394|Location.Y=412|Color=8388608|FontID=1|IsHidden=T|Text=155°C|Name=Max Operating Temperature
|RECORD=41|OwnerIndex=1027|IndexInSheet=17|OwnerPartId=-1|Location.X=394|Location.Y=412|Color=8388608|FontID=1|IsHidden=T|Text=Tape and Reel|Name=Packaging
|RECORD=41|OwnerIndex=1027|IndexInSheet=18|OwnerPartId=-1|Location.X=394|Location.Y=412|Color=8388608|FontID=1|IsHidden=T|Text=1218|Name=Case/Package
|RECORD=41|OwnerIndex=1027|IndexInSheet=19|OwnerPartId=-1|Location.X=394|Location.Y=412|Color=8388608|FontID=1|IsHidden=T|Text=0.028inch|Name=Height
|RECORD=41|OwnerIndex=1027|IndexInSheet=20|OwnerPartId=-1|Location.X=394|Location.Y=412|Color=8388608|FontID=1|IsHidden=T|Text=Yes|Name=RoHS Compliant
|RECORD=41|OwnerIndex=1027|IndexInSheet=21|OwnerPartId=-1|Location.X=394|Location.Y=412|Color=8388608|FontID=1|IsHidden=T|Text=1%|Name=Tolerance
|RECORD=41|OwnerIndex=1027|IndexInSheet=22|OwnerPartId=-1|Location.X=394|Location.Y=412|Color=8388608|FontID=1|IsHidden=T|Text=0.181inch|Name=Width
|RECORD=41|OwnerIndex=1027|IndexInSheet=23|OwnerPartId=-1|Location.X=394|Location.Y=412|Color=8388608|FontID=1|IsHidden=T|Text=4000|Name=Package Quantity
|RECORD=41|OwnerIndex=1027|IndexInSheet=24|OwnerPartId=-1|Location.X=394|Location.Y=412|Color=8388608|FontID=1|IsHidden=T|Text=Thick Film|Name=Resistor Type
|RECORD=41|OwnerIndex=1027|IndexInSheet=25|OwnerPartId=-1|Location.X=394|Location.Y=412|Color=8388608|FontID=1|IsHidden=T|Text=Automotive AEC-Q200|Name=Features
|RECORD=41|OwnerIndex=1027|IndexInSheet=26|OwnerPartId=-1|Location.X=394|Location.Y=412|Color=8388608|FontID=1|IsHidden=T|Text=Lead Free|Name=Lead Free
|RECORD=41|OwnerIndex=1027|IndexInSheet=27|OwnerPartId=-1|Location.X=394|Location.Y=412|Color=8388608|FontID=1|IsHidden=T|Text=1.5W|Name=Max Power Dissipation
|RECORD=34|OwnerIndex=1027|IndexInSheet=-1|OwnerPartId=-1|Location.X=406|Location.Y=384|Color=8388608|FontID=1|Text=R16|Name=Designator|ReadOnlyState=1
|RECORD=41|OwnerIndex=1027|IndexInSheet=-1|OwnerPartId=1|Location.X=390|Location.Y=340|Orientation=1|Color=8388608|FontID=2|Text=22_1%_1218 1.5W|Name=Comment
|RECORD=44|OwnerIndex=1027
|RECORD=45|OwnerIndex=1060|IndexInSheet=-1|UseComponentLibrary=T|ModelName=FP-CRCW1218-HPe3-MFG|ModelType=PCBLIB|IsCurrent=T|DatalinksLocked=T|DatabaseDatalinksLocked=T
|RECORD=46|OwnerIndex=1061
|RECORD=48|OwnerIndex=1061
|RECORD=45|OwnerIndex=1060|IndexInSheet=-1|UseComponentLibrary=T|ModelName=FP-CRCW1218-HPe3-IPC_A|ModelType=PCBLIB|DatalinksLocked=T|DatabaseDatalinksLocked=T
|RECORD=46|OwnerIndex=1064
|RECORD=48|OwnerIndex=1064
|RECORD=45|OwnerIndex=1060|IndexInSheet=-1|UseComponentLibrary=T|ModelName=FP-CRCW1218-HPe3-IPC_C|ModelType=PCBLIB|DatalinksLocked=T|DatabaseDatalinksLocked=T
|RECORD=46|OwnerIndex=1067
|RECORD=48|OwnerIndex=1067
|RECORD=45|OwnerIndex=1060|IndexInSheet=-1|UseComponentLibrary=T|ModelName=FP-CRCW1218-HPe3-IPC_B|ModelType=PCBLIB|DatalinksLocked=T|DatabaseDatalinksLocked=T
|RECORD=46|OwnerIndex=1070
|RECORD=48|OwnerIndex=1070
|RECORD=1|LibReference=ONSC-PMOS-G1S2D3-3_D|ComponentDescription=Small Signal MOSFET, -8 V, -3.7 A, Single P-Channel, 3-Pin SOT-23, Pb-Free, Tape and Reel|PartCount=2|DisplayModeCount=1|IndexInSheet=107|OwnerPartId=-1|Location.X=520|Location.Y=580|IsMirrored=T|Orientation=3|CurrentPartId=1|LibraryPath=*|SourceLibraryName=Altium Content Vault|TargetFileName=*|AreaColor=11599871|Color=128|PartIDLocked=T|DesignItemId=CMP-1058-00758-1|AllPinCount=3
|RECORD=2|OwnerIndex=1073|OwnerPartId=1|FormalType=1|Electrical=4|PinConglomerate=49|PinLength=20|Location.X=530|Location.Y=580|Name=G|Designator=1|SwapIDPart=Ž&Ž3|PinPropagationDelay=0.000000E+000
|RECORD=2|OwnerIndex=1073|OwnerPartId=1|FormalType=1|Electrical=4|PinConglomerate=48|PinLength=20|Location.X=540|Location.Y=560|Name=S|Designator=2|SwapIDPart=Ž&Ž3|PinPropagationDelay=0.000000E+000
|RECORD=2|OwnerIndex=1073|OwnerPartId=1|FormalType=1|Electrical=4|PinConglomerate=50|PinLength=20|Location.X=520|Location.Y=560|Name=D|Designator=3|PinPropagationDelay=0.000000E+000
|RECORD=6|OwnerIndex=1073|IsNotAccesible=T|IndexInSheet=3|OwnerPartId=1|LineWidth=1|Color=16711680|LocationCount=2|X1=523|Y1=560|X2=523|Y2=570
|RECORD=6|OwnerIndex=1073|IsNotAccesible=T|IndexInSheet=4|OwnerPartId=1|LineWidth=1|Color=16711680|LocationCount=2|X1=530|Y1=560|X2=530|Y2=570
|RECORD=6|OwnerIndex=1073|IsNotAccesible=T|IndexInSheet=5|OwnerPartId=1|LineWidth=1|Color=16711680|LocationCount=2|X1=537|Y1=560|X2=537|Y2=570
|RECORD=6|OwnerIndex=1073|IsNotAccesible=T|IndexInSheet=6|OwnerPartId=1|LineWidth=1|Color=16711680|LocationCount=2|X1=530|Y1=560|X2=540|Y2=560
|RECORD=6|OwnerIndex=1073|IsNotAccesible=T|IndexInSheet=7|OwnerPartId=1|LineWidth=1|Color=16711680|LocationCount=2|X1=521|Y1=572|X2=539|Y2=572
|RECORD=6|OwnerIndex=1073|IsNotAccesible=T|IndexInSheet=8|OwnerPartId=1|LineWidth=1|Color=16711680|LocationCount=2|X1=521|Y1=570|X2=525|Y2=570
|RECORD=6|OwnerIndex=1073|IsNotAccesible=T|IndexInSheet=9|OwnerPartId=1|LineWidth=1|Color=16711680|LocationCount=2|X1=532|Y1=570|X2=528|Y2=570
|RECORD=6|OwnerIndex=1073|IsNotAccesible=T|IndexInSheet=10|OwnerPartId=1|LineWidth=1|Color=16711680|LocationCount=2|X1=539|Y1=570|X2=535|Y2=570
|RECORD=6|OwnerIndex=1073|IsNotAccesible=T|IndexInSheet=11|OwnerPartId=1|LineWidth=1|Color=16711680|LocationCount=2|X1=523|Y1=560|X2=520|Y2=560
|RECORD=6|OwnerIndex=1073|IsNotAccesible=T|IndexInSheet=12|OwnerPartId=1|LineWidth=1|Color=16711680|LocationCount=2|X1=520|Y1=560|X2=520|Y2=550
|RECORD=6|OwnerIndex=1073|IsNotAccesible=T|IndexInSheet=13|OwnerPartId=1|LineWidth=1|Color=16711680|LocationCount=2|X1=540|Y1=560|X2=540|Y2=550
|RECORD=6|OwnerIndex=1073|IsNotAccesible=T|IndexInSheet=14|OwnerPartId=1|LineWidth=1|Color=16711680|LocationCount=2|X1=520|Y1=550|X2=527|Y2=550
|RECORD=6|OwnerIndex=1073|IsNotAccesible=T|IndexInSheet=15|OwnerPartId=1|LineWidth=1|Color=16711680|LocationCount=2|X1=540|Y1=550|X2=532|Y2=550
|RECORD=7|OwnerIndex=1073|IsNotAccesible=T|IndexInSheet=16|OwnerPartId=1|Color=16711680|AreaColor=16711680|IsSolid=T|LocationCount=3|X1=532|Y1=550|X2=527|Y2=547|X3=527|Y3=553
|RECORD=6|OwnerIndex=1073|IsNotAccesible=T|IndexInSheet=17|OwnerPartId=1|LineWidth=1|Color=16711680|LocationCount=2|X1=532|Y1=547|X2=532|Y2=553
|RECORD=6|OwnerIndex=1073|IsNotAccesible=T|IndexInSheet=18|OwnerPartId=1|LineWidth=1|Color=16711680|LocationCount=2|X1=530|Y1=580|X2=530|Y2=572
|RECORD=7|OwnerIndex=1073|IsNotAccesible=T|IndexInSheet=19|OwnerPartId=1|Color=16711680|AreaColor=16711680|IsSolid=T|LocationCount=3|X1=530|Y1=560|X2=528|Y2=566|X3=532|Y3=566
|RECORD=41|OwnerIndex=1073|IndexInSheet=20|OwnerPartId=-1|Location.X=498|Location.Y=602|Color=8388608|FontID=1|IsHidden=T|Text=Rev. 6|Name=DatasheetVersion|IsMirrored=T
|RECORD=41|OwnerIndex=1073|IndexInSheet=21|OwnerPartId=-1|Location.X=498|Location.Y=602|Color=8388608|FontID=1|IsHidden=T|Text=On Semiconductor|Name=Manufacturer|IsMirrored=T
|RECORD=41|OwnerIndex=1073|IndexInSheet=22|OwnerPartId=-1|Location.X=498|Location.Y=602|Color=8388608|FontID=3|IsHidden=T|Text=http://www.onsemi.cn/pub_link/Collateral/318-08.PDF|Name=ComponentLink3URL|IsMirrored=T
|RECORD=41|OwnerIndex=1073|IndexInSheet=23|OwnerPartId=-1|Location.X=498|Location.Y=602|Color=8388608|FontID=1|IsHidden=T|Text=Surface Mount|Name=Mounting Technology|IsMirrored=T
|RECORD=41|OwnerIndex=1073|IndexInSheet=24|OwnerPartId=-1|Location.X=498|Location.Y=602|Color=8388608|FontID=1|IsHidden=T|Text=218|Name=Crss Typ (pF)|IsMirrored=T
|RECORD=41|OwnerIndex=1073|IndexInSheet=25|OwnerPartId=-1|Location.X=498|Location.Y=602|Color=8388608|FontID=1|IsHidden=T|Text=Pb-Free|Name=RoHS|IsMirrored=T
|RECORD=41|OwnerIndex=1073|IndexInSheet=26|OwnerPartId=-1|Location.X=498|Location.Y=602|Color=8388608|FontID=1|IsHidden=T|Text=8|Name=V(BR)DSS Min (V)|IsMirrored=T
|RECORD=41|OwnerIndex=1073|IndexInSheet=27|OwnerPartId=-1|Location.X=498|Location.Y=602|Color=8388608|FontID=1|IsHidden=T|Text=1|Name=VGS(th) Max (V)|IsMirrored=T
|RECORD=41|OwnerIndex=1073|IndexInSheet=28|OwnerPartId=-1|Location.X=498|Location.Y=602|Color=8388608|FontID=1|IsHidden=T|Text=Single|Name=Configuration|IsMirrored=T
|RECORD=41|OwnerIndex=1073|IndexInSheet=29|OwnerPartId=-1|Location.X=498|Location.Y=602|Color=8388608|FontID=1|IsHidden=T|Text=Rev. AP, 11/2009|Name=PackageVersion|IsMirrored=T
|RECORD=41|OwnerIndex=1073|IndexInSheet=30|OwnerPartId=-1|Location.X=498|Location.Y=602|Color=8388608|FontID=1|IsHidden=T|Text=8|Name=VGS Max (V)|IsMirrored=T
|RECORD=41|OwnerIndex=1073|IndexInSheet=31|OwnerPartId=-1|Location.X=498|Location.Y=602|Color=8388608|FontID=1|IsHidden=T|Text=SOT-23-3-318-08|Name=PackageReference|IsMirrored=T
|RECORD=41|OwnerIndex=1073|IndexInSheet=32|OwnerPartId=-1|Location.X=498|Location.Y=602|Color=8388608|FontID=1|IsHidden=T|Text=3.7|Name=ID Max (A)|IsMirrored=T
|RECORD=41|OwnerIndex=1073|IndexInSheet=33|OwnerPartId=-1|Location.X=498|Location.Y=602|Color=8388608|FontID=1|IsHidden=T|Text=SOT-23-3|Name=Package Type|IsMirrored=T
|RECORD=41|OwnerIndex=1073|IndexInSheet=34|OwnerPartId=-1|Location.X=498|Location.Y=602|Color=8388608|FontID=1|IsHidden=T|Text=0.96|Name=PD Max (W)|IsMirrored=T
|RECORD=41|OwnerIndex=1073|IndexInSheet=35|OwnerPartId=-1|Location.X=498|Location.Y=602|Color=8388608|FontID=1|IsHidden=T|Text=NTR2101PT1G|Name=PartNumber|IsMirrored=T
|RECORD=41|OwnerIndex=1073|IndexInSheet=36|OwnerPartId=-1|Location.X=498|Location.Y=602|Color=8388608|FontID=3|IsHidden=T|Text=http://www.onsemi.cn/pub_link/Collateral/NTR2101P-D.PDF|Name=ComponentLink2URL|IsMirrored=T
|RECORD=41|OwnerIndex=1073|IndexInSheet=37|OwnerPartId=-1|Location.X=498|Location.Y=602|Color=8388608|FontID=1|IsHidden=T|Text=Datasheet|Name=ComponentLink2Description|IsMirrored=T
|RECORD=41|OwnerIndex=1073|IndexInSheet=38|OwnerPartId=-1|Location.X=498|Location.Y=602|Color=8388608|FontID=1|IsHidden=T|Text=3-Pin Small Outline Transistor, Body 2.92 x 1.3 mm, Pitch 0.95 mm|Name=PackageDescription|IsMirrored=T
|RECORD=41|OwnerIndex=1073|IndexInSheet=39|OwnerPartId=-1|Location.X=498|Location.Y=602|Color=8388608|FontID=1|IsHidden=T|Text=1173|Name=Ciss Typ (pF)|IsMirrored=T
|RECORD=41|OwnerIndex=1073|IndexInSheet=40|OwnerPartId=-1|Location.X=498|Location.Y=602|Color=8388608|FontID=1|IsHidden=T|Text=Package Specification|Name=ComponentLink3Description|IsMirrored=T
|RECORD=41|OwnerIndex=1073|IndexInSheet=41|OwnerPartId=-1|Location.X=498|Location.Y=602|Color=8388608|FontID=1|IsHidden=T|Text=Manufacturer URL|Name=ComponentLink1Description|IsMirrored=T
|RECORD=41|OwnerIndex=1073|IndexInSheet=42|OwnerPartId=-1|Location.X=498|Location.Y=602|Color=8388608|FontID=3|IsHidden=T|Text=http://www.onsemi.com/|Name=ComponentLink1URL|IsMirrored=T
|RECORD=41|OwnerIndex=1073|IndexInSheet=43|OwnerPartId=-1|Location.X=498|Location.Y=602|Color=8388608|FontID=1|IsHidden=T|Text=P Channel|Name=Channel Polarity|IsMirrored=T
|RECORD=41|OwnerIndex=1073|IndexInSheet=44|OwnerPartId=-1|Location.X=498|Location.Y=602|Color=8388608|FontID=1|IsHidden=T|Text=289|Name=Coss Typ (pF)|IsMirrored=T
|RECORD=41|OwnerIndex=1073|IndexInSheet=45|OwnerPartId=-1|Location.X=498|Location.Y=602|Color=8388608|FontID=1|IsHidden=T|Text=Tape and Reel|Name=Packing|IsMirrored=T
|RECORD=34|OwnerIndex=1073|IndexInSheet=-1|OwnerPartId=-1|Location.X=519|Location.Y=536|Color=8388608|FontID=1|Text=Q1|Name=Designator|ReadOnlyState=1|IsMirrored=T
|RECORD=41|OwnerIndex=1073|IndexInSheet=-1|OwnerPartId=-1|Location.X=519|Location.Y=526|Color=8388608|FontID=1|Text=NTR2101PT1G|Name=Comment|IsMirrored=T
|RECORD=44|OwnerIndex=1073
|RECORD=45|OwnerIndex=1125|IndexInSheet=-1|Description=SOT23, 3-Leads, Body 2.92x1.3mm, Pitch 0.95mm|UseComponentLibrary=T|ModelName=ONSC-SOT-23-3-318-08_V|ModelType=PCBLIB|IsCurrent=T|DatalinksLocked=T|DatabaseDatalinksLocked=T
|RECORD=46|OwnerIndex=1126
|RECORD=48|OwnerIndex=1126
|RECORD=41|OwnerIndex=1128|IndexInSheet=-1|OwnerPartId=-1|Color=8388608|FontID=1|IsHidden=T|Text=2D|Name=Available Preview Images
|RECORD=27|IndexInSheet=108|OwnerPartId=-1|LineWidth=1|Color=8388608|LocationCount=4|X1=400|Y1=410|X2=400|Y2=560|X3=460|Y3=560|X4=500|Y4=560
|RECORD=27|IndexInSheet=109|OwnerPartId=-1|LineWidth=1|Color=8388608|LocationCount=5|X1=560|Y1=560|X2=660|Y2=560|X3=660|Y3=690|X4=600|Y4=690|X5=600|Y5=680
|RECORD=27|IndexInSheet=110|OwnerPartId=-1|LineWidth=1|Color=8388608|LocationCount=6|X1=530|Y1=600|X2=530|Y2=610|X3=600|Y3=610|X4=820|Y4=610|X5=820|Y5=490|X6=800|Y6=490
|RECORD=29|IndexInSheet=-1|OwnerPartId=-1|Location.X=170|Location.Y=280|Color=128
|RECORD=29|IndexInSheet=-1|OwnerPartId=-1|Location.X=280|Location.Y=300|Color=128
|RECORD=29|IndexInSheet=-1|OwnerPartId=-1|Location.X=290|Location.Y=300|Color=128
|RECORD=29|IndexInSheet=-1|OwnerPartId=-1|Location.X=400|Location.Y=300|Color=128
|RECORD=29|IndexInSheet=-1|OwnerPartId=-1|Location.X=460|Location.Y=410|Color=128
|RECORD=29|IndexInSheet=-1|OwnerPartId=-1|Location.X=460|Location.Y=560|Color=128
|RECORD=29|IndexInSheet=-1|OwnerPartId=-1|Location.X=490|Location.Y=300|Color=128
|RECORD=29|IndexInSheet=-1|OwnerPartId=-1|Location.X=540|Location.Y=490|Color=128
|RECORD=29|IndexInSheet=-1|OwnerPartId=-1|Location.X=600|Location.Y=610|Color=128
|RECORD=29|IndexInSheet=-1|OwnerPartId=-1|Location.X=660|Location.Y=690|Color=128
|RECORD=29|IndexInSheet=-1|OwnerPartId=-1|Location.X=700|Location.Y=290|Color=128